FILE_TYPE = MACRO_DRAWING;
SET COLOR_WIRE YELLOW;
SET COLOR_PROP MONO;
SET COLOR_DOT WHITE;
SET COLOR_ARC YELLOW;
SET COLOR_BODY GREEN;
SET COLOR_NOTE MONO;
SET PROP_DISPLAY VALUE;
SET PAGE_NUMBER P205;
FORCEADD OFFPAGE..2
(-1275 4875);
FORCEPROP 2 LAST $XR0 201 
J 0
(-1086 4875);
DISPLAY 0.638298 (-1086 4875);
PAINT MONO (-1086 4875);
FORCEPROP 2 LAST CDS_LIB mstr_standard
J 0
(-1275 4875);
PAINT ORANGE (-1275 4875);
DISPLAY INVISIBLE (-1275 4875);
FORCEPROP 2 LAST ROOM PVSA_CPU0_PWR_VR
J 0
(-1675 4950);
DISPLAY 1.936170 (-1675 4950);
PAINT ORANGE (-1675 4950);
DISPLAY INVISIBLE (-1675 4950);
FORCEPROP 2 LAST PATH I1
J 0
(-1095 4950);
DISPLAY 1.021277 (-1095 4950);
PAINT ORANGE (-1095 4950);
DISPLAY INVISIBLE (-1095 4950);
FORCEPROP 2 LAST BOM_COST PROC_VRD_VCCIN_CPU0
J 0
(-1075 4925);
DISPLAY 1.446809 (-1075 4925);
PAINT MONO (-1075 4925);
DISPLAY INVISIBLE (-1075 4925);
FORCEPROP 1 LAST OFFPAGE TRUE
J 0
(-950 4750);
DISPLAY 1.723404 (-950 4750);
PAINT GREEN (-950 4750);
DISPLAY INVISIBLE (-950 4750);
FORCEPROP 1 LAST COMMENT_BODY TRUE
J 0
(-1320 4780);
DISPLAY 1.723404 (-1320 4780);
PAINT GREEN (-1320 4780);
DISPLAY INVISIBLE (-1320 4780);
FORCEADD PVSA_CPU0..1
(-2000 1600);
FORCEPROP 3 LASTPIN (-2000 1550) SIG_NAME PVSA_CPU0\g
J 0
(-1990 1560);
DISPLAY 0.659574 (-1990 1560);
PAINT MONO (-1990 1560);
DISPLAY INVISIBLE (-1990 1560);
FORCEPROP 1 LAST PATH I11
J 0
(-1950 1625);
DISPLAY 0.872340 (-1950 1625);
PAINT AQUA (-1950 1625);
DISPLAY INVISIBLE (-1950 1625);
FORCEPROP 2 LAST CDS_LIB mstr_symbols
J 0
(-2000 1600);
PAINT ORANGE (-2000 1600);
DISPLAY INVISIBLE (-2000 1600);
FORCEPROP 1 LAST VOLTAGE 1.1V
J 0
(-2045 1557);
DISPLAY 0.340426 (-2045 1557);
PAINT SKYBLUE (-2045 1557);
DISPLAY INVISIBLE (-2045 1557);
FORCEPROP 1 LAST BODY_TYPE PLUMBING
J 0
(-2045 1557);
DISPLAY 0.340426 (-2045 1557);
PAINT GREEN (-2045 1557);
DISPLAY INVISIBLE (-2045 1557);
FORCEPROP 1 LAST HDL_POWER PVSA_CPU0
J 1
(-2000 1650);
DISPLAY 0.872340 (-2000 1650);
PAINT GREEN (-2000 1650);
DISPLAY INVISIBLE (-2000 1650);
FORCEADD CAPP..1
(-2000 1350);
FORCEPROP 1 LAST VOLTAGE 2.5V
J 0
(-1950 1300);
DISPLAY 0.617021 (-1950 1300);
PAINT SKYBLUE (-1950 1300);
FORCEPROP 1 LASTPIN (-2000 1250) $PN 2
J 0
(-1990 1235);
DISPLAY 0.617021 (-1990 1235);
PAINT ORANGE (-1990 1235);
FORCEPROP 1 LASTPIN (-2000 1450) $PN 1
J 0
(-1990 1435);
DISPLAY 0.617021 (-1990 1435);
PAINT ORANGE (-1990 1435);
FORCEPROP 1 LAST PART_NUMBER 699013-049
J 0
(-1950 1150);
DISPLAY 0.617021 (-1950 1150);
PAINT BLUE (-1950 1150);
FORCEPROP 1 LAST LOCATION C6N1
J 0
(-1950 1450);
DISPLAY 0.617021 (-1950 1450);
PAINT AQUA (-1950 1450);
FORCEPROP 1 LAST VALUE 470UF
J 0
(-1950 1400);
DISPLAY 0.617021 (-1950 1400);
PAINT SKYBLUE (-1950 1400);
FORCEPROP 1 LAST TOLERANCE 20%
J 0
(-1950 1350);
DISPLAY 0.617021 (-1950 1350);
PAINT SKYBLUE (-1950 1350);
FORCEPROP 0 LAST GROUP PWR_BULK_CAP
J 0
(-1945 1106);
DISPLAY 0.638298 (-1945 1106);
PAINT BROWN (-1945 1106);
DISPLAY BOTH (-1945 1106);
FORCEPROP 1 LAST PACK_TYPE 3018
J 0
(-1950 1200);
DISPLAY 0.617021 (-1950 1200);
PAINT SKYBLUE (-1950 1200);
FORCEPROP 1 LAST MATERIAL ALUM
J 0
(-1950 1250);
DISPLAY 0.617021 (-1950 1250);
PAINT SKYBLUE (-1950 1250);
FORCEPROP 2 LAST CDS_LIB mstr_discrete
J 0
(-2000 1350);
PAINT ORANGE (-2000 1350);
DISPLAY INVISIBLE (-2000 1350);
FORCEPROP 2 LAST CDS_LOCATION C6N1
J 0
(-1950 1450);
DISPLAY 0.617021 (-1950 1450);
PAINT AQUA (-1950 1450);
DISPLAY INVISIBLE (-1950 1450);
FORCEPROP 2 LAST ROOM PVSA_CPU0_DECAP_VR
J 0
(-1950 1475);
PAINT MONO (-1950 1475);
DISPLAY INVISIBLE (-1950 1475);
FORCEPROP 1 LAST PATH I12
J 0
(-1950 1500);
DISPLAY 0.978723 (-1950 1500);
PAINT ORANGE (-1950 1500);
DISPLAY INVISIBLE (-1950 1500);
FORCEPROP 2 LAST BOM_COST PROC_VRD_VCCIN_CPU0
J 0
(-1950 1500);
PAINT MONO (-1950 1500);
DISPLAY INVISIBLE (-1950 1500);
FORCEPROP 2 LAST SEC 1
J 0
(-1950 1550);
PAINT MONO (-1950 1550);
DISPLAY INVISIBLE (-1950 1550);
FORCEPROP 2 LAST SEC_TYPE 3018
J 0
(-1945 1570);
DISPLAY 1.021277 (-1945 1570);
PAINT ORANGE (-1945 1570);
DISPLAY INVISIBLE (-1945 1570);
FORCEADD GND..1
(-2000 975);
FORCEPROP 3 LASTPIN (-2000 1025) SIG_NAME GND\g
J 0
(-1990 1035);
DISPLAY 0.659574 (-1990 1035);
PAINT MONO (-1990 1035);
DISPLAY INVISIBLE (-1990 1035);
FORCEPROP 2 LAST CDS_LIB mstr_symbols
J 0
(-2000 975);
PAINT ORANGE (-2000 975);
DISPLAY INVISIBLE (-2000 975);
FORCEPROP 1 LAST SIZE 1B
J 0
(-1925 925);
DISPLAY 1.723404 (-1925 925);
PAINT GREEN (-1925 925);
DISPLAY INVISIBLE (-1925 925);
FORCEPROP 1 LAST PATH I13
J 0
(-1925 975);
DISPLAY 0.872340 (-1925 975);
PAINT AQUA (-1925 975);
DISPLAY INVISIBLE (-1925 975);
FORCEPROP 1 LAST VOLTAGE 0
J 0
(-2000 975);
PAINT SKYBLUE (-2000 975);
DISPLAY INVISIBLE (-2000 975);
FORCEPROP 2 LAST BOM_COST PROC_VRD_VCCIN_CPU0
J 0
(-2375 1050);
DISPLAY 1.446809 (-2375 1050);
PAINT MONO (-2375 1050);
DISPLAY INVISIBLE (-2375 1050);
FORCEPROP 2 LAST ROOM PVSA_CPU0_DECAP_VR
J 0
(-2550 1050);
DISPLAY 1.936170 (-2550 1050);
PAINT ORANGE (-2550 1050);
DISPLAY INVISIBLE (-2550 1050);
FORCEPROP 1 LAST BODY_TYPE PLUMBING
J 0
(-2045 932);
DISPLAY 0.340426 (-2045 932);
PAINT GREEN (-2045 932);
DISPLAY INVISIBLE (-2045 932);
FORCEPROP 1 LAST HDL_POWER GND
J 0
(-2000 1125);
DISPLAY 1.723404 (-2000 1125);
PAINT GREEN (-2000 1125);
DISPLAY INVISIBLE (-2000 1125);
FORCEADD CAPP..1
R 2
(-2650 1350);
FORCEPROP 1 LAST VOLTAGE 2.5V
J 0
(-2600 1300);
DISPLAY 0.617021 (-2600 1300);
PAINT SKYBLUE (-2600 1300);
FORCEPROP 1 LASTPIN (-2650 1250) $PN 2
J 2
(-2660 1235);
DISPLAY 0.617021 (-2660 1235);
PAINT GREEN (-2660 1235);
FORCEPROP 1 LASTPIN (-2650 1450) $PN 1
J 2
(-2660 1435);
DISPLAY 0.617021 (-2660 1435);
PAINT GREEN (-2660 1435);
FORCEPROP 1 LAST MATERIAL ALUM
J 0
(-2600 1250);
DISPLAY 0.617021 (-2600 1250);
PAINT SKYBLUE (-2600 1250);
FORCEPROP 1 LAST PART_NUMBER 699013-049
J 0
(-2600 1150);
DISPLAY 0.617021 (-2600 1150);
PAINT BLUE (-2600 1150);
FORCEPROP 1 LAST VALUE 470UF
J 0
(-2600 1400);
DISPLAY 0.617021 (-2600 1400);
PAINT SKYBLUE (-2600 1400);
FORCEPROP 1 LAST LOCATION C6N4
J 0
(-2600 1450);
DISPLAY 0.617021 (-2600 1450);
PAINT AQUA (-2600 1450);
FORCEPROP 1 LAST PACK_TYPE 3018
J 0
(-2600 1200);
DISPLAY 0.617021 (-2600 1200);
PAINT SKYBLUE (-2600 1200);
FORCEPROP 1 LAST TOLERANCE 20%
J 0
(-2600 1350);
DISPLAY 0.617021 (-2600 1350);
PAINT SKYBLUE (-2600 1350);
FORCEPROP 0 LAST GROUP PWR_BULK_CAP
J 0
(-2595 1106);
DISPLAY 0.638298 (-2595 1106);
PAINT BROWN (-2595 1106);
DISPLAY BOTH (-2595 1106);
FORCEPROP 2 LAST BOM_COST PROC_VRD_VCCIN_CPU0
J 0
(-2700 1500);
PAINT MONO (-2700 1500);
DISPLAY INVISIBLE (-2700 1500);
FORCEPROP 1 LAST PATH I14
J 0
(-2700 1500);
DISPLAY 0.978723 (-2700 1500);
PAINT ORANGE (-2700 1500);
DISPLAY INVISIBLE (-2700 1500);
FORCEPROP 2 LAST ROOM PVSA_CPU0_DECAP_VR
J 0
(-2700 1475);
PAINT MONO (-2700 1475);
DISPLAY INVISIBLE (-2700 1475);
FORCEPROP 2 LAST CDS_LIB mstr_discrete
J 2
(-2650 1350);
PAINT ORANGE (-2650 1350);
DISPLAY INVISIBLE (-2650 1350);
FORCEPROP 2 LAST CDS_LOCATION C6N4
J 2
(-2700 1450);
DISPLAY 0.617021 (-2700 1450);
PAINT AQUA (-2700 1450);
DISPLAY INVISIBLE (-2700 1450);
FORCEPROP 2 LAST SEC 1
J 0
(-2690 1565);
DISPLAY 0.680851 (-2690 1565);
PAINT MONO (-2690 1565);
DISPLAY INVISIBLE (-2690 1565);
FORCEPROP 2 LAST SEC_TYPE 3018
J 0
(-2690 1565);
DISPLAY 1.021277 (-2690 1565);
PAINT ORANGE (-2690 1565);
DISPLAY INVISIBLE (-2690 1565);
FORCEADD GND..1
(-2475 3275);
FORCEPROP 3 LASTPIN (-2475 3325) SIG_NAME GND\g
J 0
(-2465 3335);
DISPLAY 0.659574 (-2465 3335);
PAINT MONO (-2465 3335);
DISPLAY INVISIBLE (-2465 3335);
FORCEPROP 2 LAST ROOM PVSA_CPU0_PWR_VR
J 0
(-3025 3350);
DISPLAY 1.936170 (-3025 3350);
PAINT ORANGE (-3025 3350);
DISPLAY INVISIBLE (-3025 3350);
FORCEPROP 2 LAST BOM_COST PROC_VRD_VCCIN_CPU0
J 0
(-2850 3350);
DISPLAY 1.446809 (-2850 3350);
PAINT MONO (-2850 3350);
DISPLAY INVISIBLE (-2850 3350);
FORCEPROP 1 LAST SIZE 1B
J 0
(-2400 3225);
DISPLAY 1.723404 (-2400 3225);
PAINT GREEN (-2400 3225);
DISPLAY INVISIBLE (-2400 3225);
FORCEPROP 1 LAST VOLTAGE 0
J 0
(-2475 3275);
PAINT SKYBLUE (-2475 3275);
DISPLAY INVISIBLE (-2475 3275);
FORCEPROP 2 LAST CDS_LIB mstr_symbols
J 0
(-2475 3275);
PAINT ORANGE (-2475 3275);
DISPLAY INVISIBLE (-2475 3275);
FORCEPROP 1 LAST PATH I15
J 0
(-2400 3275);
DISPLAY 0.872340 (-2400 3275);
PAINT AQUA (-2400 3275);
DISPLAY INVISIBLE (-2400 3275);
FORCEPROP 1 LAST BODY_TYPE PLUMBING
J 0
(-2520 3232);
DISPLAY 0.340426 (-2520 3232);
PAINT GREEN (-2520 3232);
DISPLAY INVISIBLE (-2520 3232);
FORCEPROP 1 LAST HDL_POWER GND
J 0
(-2475 3425);
DISPLAY 1.723404 (-2475 3425);
PAINT GREEN (-2475 3425);
DISPLAY INVISIBLE (-2475 3425);
FORCEADD CAP..1
(-5300 4200);
FORCEPROP 1 LAST LOCATION C4C5
J 0
(-5250 4300);
DISPLAY 0.617021 (-5250 4300);
PAINT AQUA (-5250 4300);
FORCEPROP 1 LASTPIN (-5300 4300) $PN 1
J 0
(-5290 4280);
DISPLAY 0.617021 (-5290 4280);
PAINT ORANGE (-5290 4280);
FORCEPROP 1 LAST VALUE 0.22UF
J 0
(-5250 4250);
DISPLAY 0.617021 (-5250 4250);
PAINT SKYBLUE (-5250 4250);
FORCEPROP 1 LAST MATERIAL X7R
J 0
(-5100 4300);
DISPLAY 0.617021 (-5100 4300);
PAINT SKYBLUE (-5100 4300);
FORCEPROP 1 LAST VOLTAGE 16V
J 0
(-5250 4200);
DISPLAY 0.617021 (-5250 4200);
PAINT SKYBLUE (-5250 4200);
FORCEPROP 1 LAST PACK_TYPE 0402
J 0
(-5100 4200);
DISPLAY 0.617021 (-5100 4200);
PAINT SKYBLUE (-5100 4200);
FORCEPROP 1 LASTPIN (-5300 4100) $PN 2
J 0
(-5290 4080);
DISPLAY 0.617021 (-5290 4080);
PAINT ORANGE (-5290 4080);
FORCEPROP 1 LAST PART_NUMBER A36096-155
J 0
(-5100 4250);
DISPLAY 0.617021 (-5100 4250);
PAINT BLUE (-5100 4250);
FORCEPROP 1 LAST TOLERANCE 10%
J 0
(-5250 4150);
DISPLAY 0.617021 (-5250 4150);
PAINT SKYBLUE (-5250 4150);
FORCEPROP 2 LAST CDS_LIB mstr_discrete
J 0
(-5300 4200);
PAINT ORANGE (-5300 4200);
DISPLAY INVISIBLE (-5300 4200);
FORCEPROP 2 LAST SEC_TYPE 0402
J 0
(-5250 4400);
DISPLAY 1.021277 (-5250 4400);
PAINT ORANGE (-5250 4400);
DISPLAY INVISIBLE (-5250 4400);
FORCEPROP 2 LAST SEC 1
J 0
(-5250 4400);
DISPLAY 0.680851 (-5250 4400);
PAINT MONO (-5250 4400);
DISPLAY INVISIBLE (-5250 4400);
FORCEPROP 2 LAST CDS_LOCATION C4C5
J 0
(-5250 4300);
DISPLAY 0.617021 (-5250 4300);
PAINT AQUA (-5250 4300);
DISPLAY INVISIBLE (-5250 4300);
FORCEPROP 1 LAST PATH I16
J 0
(-5250 4350);
DISPLAY 0.978723 (-5250 4350);
PAINT WHITE (-5250 4350);
DISPLAY INVISIBLE (-5250 4350);
FORCEPROP 2 LAST ROOM PVSA_CPU0_PWR_VR
J 0
(-5250 4350);
DISPLAY 1.361702 (-5250 4350);
PAINT ORANGE (-5250 4350);
DISPLAY INVISIBLE (-5250 4350);
FORCEADD OFFPAGE..2
(-1350 4475);
FORCEPROP 2 LAST $XR0 201 
J 0
(-1161 4475);
DISPLAY 0.638298 (-1161 4475);
PAINT MONO (-1161 4475);
FORCEPROP 2 LAST ROOM PVSA_CPU0_PWR_VR
J 0
(-1750 4550);
DISPLAY 1.936170 (-1750 4550);
PAINT ORANGE (-1750 4550);
DISPLAY INVISIBLE (-1750 4550);
FORCEPROP 2 LAST CDS_LIB mstr_standard
J 0
(-1350 4475);
PAINT ORANGE (-1350 4475);
DISPLAY INVISIBLE (-1350 4475);
FORCEPROP 2 LAST BOM_COST PROC_VRD_VCCIN_CPU0
J 0
(-1150 4525);
DISPLAY 1.446809 (-1150 4525);
PAINT MONO (-1150 4525);
DISPLAY INVISIBLE (-1150 4525);
FORCEPROP 2 LAST PATH I2
J 0
(-1170 4550);
DISPLAY 1.021277 (-1170 4550);
PAINT ORANGE (-1170 4550);
DISPLAY INVISIBLE (-1170 4550);
FORCEPROP 1 LAST OFFPAGE TRUE
J 0
(-1025 4350);
DISPLAY 1.723404 (-1025 4350);
PAINT GREEN (-1025 4350);
DISPLAY INVISIBLE (-1025 4350);
FORCEPROP 1 LAST COMMENT_BODY TRUE
J 0
(-1395 4380);
DISPLAY 1.723404 (-1395 4380);
PAINT GREEN (-1395 4380);
DISPLAY INVISIBLE (-1395 4380);
FORCEADD CAP..1
(-6000 4200);
FORCEPROP 1 LAST PACK_TYPE 0402
J 0
(-5950 4000);
DISPLAY 0.617021 (-5950 4000);
PAINT SKYBLUE (-5950 4000);
FORCEPROP 1 LAST PART_NUMBER D97712-011
J 0
(-5950 4050);
DISPLAY 0.617021 (-5950 4050);
PAINT BLUE (-5950 4050);
FORCEPROP 1 LAST TOLERANCE 10%
J 0
(-5950 4150);
DISPLAY 0.617021 (-5950 4150);
PAINT SKYBLUE (-5950 4150);
FORCEPROP 1 LAST VOLTAGE 16V
J 0
(-5950 4200);
DISPLAY 0.617021 (-5950 4200);
PAINT SKYBLUE (-5950 4200);
FORCEPROP 1 LAST MATERIAL X6S
J 0
(-5950 4100);
DISPLAY 0.617021 (-5950 4100);
PAINT SKYBLUE (-5950 4100);
FORCEPROP 1 LASTPIN (-6000 4100) $PN 2
J 0
(-5990 4080);
DISPLAY 0.617021 (-5990 4080);
PAINT ORANGE (-5990 4080);
FORCEPROP 1 LAST VALUE 1.0UF
J 0
(-5950 4250);
DISPLAY 0.617021 (-5950 4250);
PAINT SKYBLUE (-5950 4250);
FORCEPROP 1 LAST LOCATION C4C6
J 0
(-5950 4300);
DISPLAY 0.617021 (-5950 4300);
PAINT AQUA (-5950 4300);
FORCEPROP 1 LASTPIN (-6000 4300) $PN 1
J 0
(-5990 4280);
DISPLAY 0.617021 (-5990 4280);
PAINT ORANGE (-5990 4280);
FORCEPROP 2 LAST ROOM PVSA_CPU0_PWR_VR
J 0
(-5950 4350);
DISPLAY 1.361702 (-5950 4350);
PAINT ORANGE (-5950 4350);
DISPLAY INVISIBLE (-5950 4350);
FORCEPROP 1 LAST PATH I20
J 0
(-5950 4350);
DISPLAY 0.978723 (-5950 4350);
PAINT WHITE (-5950 4350);
DISPLAY INVISIBLE (-5950 4350);
FORCEPROP 2 LAST SEC 1
J 0
(-5950 4400);
DISPLAY 0.680851 (-5950 4400);
PAINT MONO (-5950 4400);
DISPLAY INVISIBLE (-5950 4400);
FORCEPROP 2 LAST SEC_TYPE 0402
J 0
(-5950 4400);
DISPLAY 1.021277 (-5950 4400);
PAINT ORANGE (-5950 4400);
DISPLAY INVISIBLE (-5950 4400);
FORCEPROP 2 LAST CDS_LIB mstr_discrete
J 0
(-6000 4200);
PAINT ORANGE (-6000 4200);
DISPLAY INVISIBLE (-6000 4200);
FORCEPROP 2 LAST CDS_LOCATION C4C6
J 0
(-5950 4300);
DISPLAY 0.617021 (-5950 4300);
PAINT AQUA (-5950 4300);
DISPLAY INVISIBLE (-5950 4300);
FORCEADD OFFPAGE..2
(-3750 2025);
FORCEPROP 2 LAST $XR0 39 
J 0
(-3561 2025);
DISPLAY 0.638298 (-3561 2025);
PAINT MONO (-3561 2025);
FORCEPROP 2 LAST BOM_COST PROC_VRD_VCCIN_CPU0
J 0
(-3425 2075);
PAINT MONO (-3425 2075);
DISPLAY INVISIBLE (-3425 2075);
FORCEPROP 2 LAST PATH I22
J 0
(-3585 2085);
DISPLAY 1.021277 (-3585 2085);
PAINT ORANGE (-3585 2085);
DISPLAY INVISIBLE (-3585 2085);
FORCEPROP 2 LAST CDS_LIB mstr_standard
J 0
(-3750 2025);
PAINT ORANGE (-3750 2025);
DISPLAY INVISIBLE (-3750 2025);
FORCEPROP 2 LAST ROOM PVSA_CPU0_VSENSE_VR
J 0
(-4150 2100);
PAINT ORANGE (-4150 2100);
DISPLAY INVISIBLE (-4150 2100);
FORCEPROP 1 LAST OFFPAGE TRUE
J 0
(-3425 1900);
DISPLAY 0.893617 (-3425 1900);
PAINT GREEN (-3425 1900);
DISPLAY INVISIBLE (-3425 1900);
FORCEPROP 1 LAST COMMENT_BODY TRUE
J 0
(-3795 1930);
DISPLAY 0.893617 (-3795 1930);
PAINT GREEN (-3795 1930);
DISPLAY INVISIBLE (-3795 1930);
FORCEADD PVSA_CPU0..1
(-4300 2650);
FORCEPROP 3 LASTPIN (-4300 2600) SIG_NAME PVSA_CPU0\g
J 0
(-4290 2610);
DISPLAY 0.659574 (-4290 2610);
PAINT MONO (-4290 2610);
DISPLAY INVISIBLE (-4290 2610);
FORCEPROP 2 LAST ROOM PVSA_CPU0_VSENSE_VR
J 0
(-4050 2750);
PAINT ORANGE (-4050 2750);
DISPLAY INVISIBLE (-4050 2750);
FORCEPROP 1 LAST PATH I23
J 0
(-4250 2675);
DISPLAY 0.872340 (-4250 2675);
PAINT AQUA (-4250 2675);
DISPLAY INVISIBLE (-4250 2675);
FORCEPROP 2 LAST CDS_LIB mstr_symbols
J 0
(-4300 2650);
PAINT ORANGE (-4300 2650);
DISPLAY INVISIBLE (-4300 2650);
FORCEPROP 2 LAST BOM_COST PROC_VRD_VCCIN_CPU0
J 0
(-4275 2750);
PAINT MONO (-4275 2750);
DISPLAY INVISIBLE (-4275 2750);
FORCEPROP 1 LAST VOLTAGE 1.1V
J 0
(-4345 2607);
DISPLAY 0.340426 (-4345 2607);
PAINT SKYBLUE (-4345 2607);
DISPLAY INVISIBLE (-4345 2607);
FORCEPROP 1 LAST BODY_TYPE PLUMBING
J 0
(-4345 2607);
DISPLAY 0.340426 (-4345 2607);
PAINT GREEN (-4345 2607);
DISPLAY INVISIBLE (-4345 2607);
FORCEPROP 1 LAST HDL_POWER PVSA_CPU0
J 1
(-4300 2700);
DISPLAY 0.872340 (-4300 2700);
PAINT GREEN (-4300 2700);
DISPLAY INVISIBLE (-4300 2700);
FORCEADD RES..1
(-5100 2425);
FORCEPROP 1 LASTPIN (-5200 2425) $PN 1
J 0
(-5188 2437);
DISPLAY 0.617021 (-5188 2437);
PAINT ORANGE (-5188 2437);
FORCEPROP 1 LAST PART_NUMBER G21796-017
J 0
(-5150 2525);
DISPLAY 0.617021 (-5150 2525);
PAINT BLUE (-5150 2525);
FORCEPROP 1 LAST LOCATION R4C5
J 0
(-5150 2475);
DISPLAY 0.617021 (-5150 2475);
PAINT AQUA (-5150 2475);
FORCEPROP 1 LASTPIN (-5000 2425) $PN 2
J 0
(-5038 2437);
DISPLAY 0.617021 (-5038 2437);
PAINT ORANGE (-5038 2437);
FORCEPROP 1 LAST WATTAGE 1/16W
J 2
(-5100 2300);
DISPLAY 0.617021 (-5100 2300);
PAINT SKYBLUE (-5100 2300);
FORCEPROP 1 LAST PACK_TYPE 0402
J 0
(-5175 2250);
DISPLAY 0.617021 (-5175 2250);
PAINT SKYBLUE (-5175 2250);
FORCEPROP 1 LAST MATERIAL CHIP
J 0
(-5075 2300);
DISPLAY 0.638298 (-5075 2300);
PAINT SKYBLUE (-5075 2300);
FORCEPROP 1 LAST TOLERANCE 1%
J 0
(-5050 2350);
DISPLAY 0.617021 (-5050 2350);
PAINT SKYBLUE (-5050 2350);
FORCEPROP 1 LAST VALUE 100.0
J 2
(-5100 2350);
DISPLAY 0.617021 (-5100 2350);
PAINT SKYBLUE (-5100 2350);
FORCEPROP 2 LAST CDS_LIB mstr_discrete
J 0
(-5100 2425);
PAINT ORANGE (-5100 2425);
DISPLAY INVISIBLE (-5100 2425);
FORCEPROP 2 LAST SEC_TYPE 0402
J 0
(-5135 2635);
DISPLAY 1.021277 (-5135 2635);
PAINT ORANGE (-5135 2635);
DISPLAY INVISIBLE (-5135 2635);
FORCEPROP 2 LAST SEC 1
J 0
(-5135 2635);
DISPLAY 0.680851 (-5135 2635);
PAINT MONO (-5135 2635);
DISPLAY INVISIBLE (-5135 2635);
FORCEPROP 2 LAST BOM_COST PROC_VRD_VCCIN_CPU0
J 0
(-5150 2575);
PAINT MONO (-5150 2575);
DISPLAY INVISIBLE (-5150 2575);
FORCEPROP 1 LAST PATH I24
J 0
(-5150 2575);
DISPLAY 0.978723 (-5150 2575);
PAINT WHITE (-5150 2575);
DISPLAY INVISIBLE (-5150 2575);
FORCEPROP 2 LAST ROOM PVSA_CPU0_VSENSE_VR
J 0
(-5150 2525);
PAINT ORANGE (-5150 2525);
DISPLAY INVISIBLE (-5150 2525);
FORCEPROP 2 LAST CDS_LOCATION R4C5
J 0
(-5150 2475);
DISPLAY 0.617021 (-5150 2475);
PAINT AQUA (-5150 2475);
DISPLAY INVISIBLE (-5150 2475);
FORCEADD CAP..1
R 2
(-6050 3550);
FORCEPROP 1 LASTPIN (-6050 3450) $PN 2
J 2
(-6060 3430);
DISPLAY 0.617021 (-6060 3430);
PAINT ORANGE (-6060 3430);
FORCEPROP 1 LAST LOCATION C4C8
J 2
(-6100 3650);
DISPLAY 0.617021 (-6100 3650);
PAINT AQUA (-6100 3650);
FORCEPROP 1 LASTPIN (-6050 3650) $PN 1
J 2
(-6060 3630);
DISPLAY 0.617021 (-6060 3630);
PAINT ORANGE (-6060 3630);
FORCEPROP 1 LAST VALUE 0.220UF
J 2
(-6100 3600);
DISPLAY 0.617021 (-6100 3600);
PAINT SKYBLUE (-6100 3600);
FORCEPROP 1 LAST VOLTAGE 16V
J 2
(-6100 3550);
DISPLAY 0.617021 (-6100 3550);
PAINT SKYBLUE (-6100 3550);
FORCEPROP 1 LAST MATERIAL X7R
J 2
(-6100 3450);
DISPLAY 0.617021 (-6100 3450);
PAINT SKYBLUE (-6100 3450);
FORCEPROP 1 LAST PART_NUMBER A36096-104
J 2
(-6100 3400);
DISPLAY 0.617021 (-6100 3400);
PAINT BLUE (-6100 3400);
FORCEPROP 1 LAST PACK_TYPE 0402
J 2
(-6100 3350);
DISPLAY 0.617021 (-6100 3350);
PAINT SKYBLUE (-6100 3350);
FORCEPROP 1 LAST TOLERANCE 10%
J 2
(-6100 3500);
DISPLAY 0.617021 (-6100 3500);
PAINT SKYBLUE (-6100 3500);
FORCEPROP 2 LAST SEC 1
J 0
(-6100 3750);
DISPLAY 0.680851 (-6100 3750);
PAINT MONO (-6100 3750);
DISPLAY INVISIBLE (-6100 3750);
FORCEPROP 2 LAST SEC_TYPE 0402
J 0
(-6100 3750);
DISPLAY 1.021277 (-6100 3750);
PAINT ORANGE (-6100 3750);
DISPLAY INVISIBLE (-6100 3750);
FORCEPROP 0 LAST SPOF TRUE
J 0
(-6100 3750);
DISPLAY 1.021277 (-6100 3750);
PAINT ORANGE (-6100 3750);
DISPLAY INVISIBLE (-6100 3750);
FORCEPROP 2 LAST ROOM PVSA_CPU0_PWR_VR
J 0
(-6100 3700);
DISPLAY 1.361702 (-6100 3700);
PAINT ORANGE (-6100 3700);
DISPLAY INVISIBLE (-6100 3700);
FORCEPROP 1 LAST PATH I25
J 2
(-6100 3700);
DISPLAY 0.978723 (-6100 3700);
PAINT WHITE (-6100 3700);
DISPLAY INVISIBLE (-6100 3700);
FORCEPROP 2 LAST CDS_LOCATION C4C8
J 2
(-6100 3650);
DISPLAY 0.617021 (-6100 3650);
PAINT AQUA (-6100 3650);
DISPLAY INVISIBLE (-6100 3650);
FORCEPROP 2 LAST CDS_LIB mstr_discrete
J 0
(-6050 3550);
PAINT ORANGE (-6050 3550);
DISPLAY INVISIBLE (-6050 3550);
FORCEADD RES..1
(-5075 2025);
FORCEPROP 1 LASTPIN (-5175 2025) $PN 1
J 0
(-5163 2037);
DISPLAY 0.617021 (-5163 2037);
PAINT ORANGE (-5163 2037);
FORCEPROP 1 LASTPIN (-4975 2025) $PN 2
J 0
(-5013 2037);
DISPLAY 0.617021 (-5013 2037);
PAINT ORANGE (-5013 2037);
FORCEPROP 1 LAST MATERIAL CHIP
J 0
(-5075 1875);
DISPLAY 0.617021 (-5075 1875);
PAINT SKYBLUE (-5075 1875);
FORCEPROP 1 LAST PACK_TYPE 0402
J 0
(-5200 1825);
DISPLAY 0.617021 (-5200 1825);
PAINT SKYBLUE (-5200 1825);
FORCEPROP 1 LAST WATTAGE 1/16W
J 2
(-5100 1875);
DISPLAY 0.617021 (-5100 1875);
PAINT SKYBLUE (-5100 1875);
FORCEPROP 1 LAST VALUE 0.0
J 2
(-5100 1950);
DISPLAY 0.617021 (-5100 1950);
PAINT SKYBLUE (-5100 1950);
FORCEPROP 1 LAST LOCATION R4C4
J 0
(-5125 2075);
DISPLAY 0.617021 (-5125 2075);
PAINT AQUA (-5125 2075);
FORCEPROP 1 LAST PART_NUMBER G21497-005
J 0
(-5200 2125);
DISPLAY 0.617021 (-5200 2125);
PAINT BLUE (-5200 2125);
FORCEPROP 1 LAST TOLERANCE 5%
J 0
(-5075 1950);
DISPLAY 0.617021 (-5075 1950);
PAINT SKYBLUE (-5075 1950);
FORCEPROP 2 LAST SEC 1
J 0
(-5110 2235);
DISPLAY 0.680851 (-5110 2235);
PAINT MONO (-5110 2235);
DISPLAY INVISIBLE (-5110 2235);
FORCEPROP 2 LAST SEC_TYPE 0402
J 0
(-5110 2235);
DISPLAY 1.021277 (-5110 2235);
PAINT ORANGE (-5110 2235);
DISPLAY INVISIBLE (-5110 2235);
FORCEPROP 2 LAST BOM_COST PROC_VRD_VCCIN_CPU0
J 0
(-5200 2175);
PAINT MONO (-5200 2175);
DISPLAY INVISIBLE (-5200 2175);
FORCEPROP 2 LAST CDS_LOCATION R4C4
J 0
(-5125 2075);
DISPLAY 0.617021 (-5125 2075);
PAINT AQUA (-5125 2075);
DISPLAY INVISIBLE (-5125 2075);
FORCEPROP 1 LAST PATH I26
J 0
(-5125 2175);
DISPLAY 0.978723 (-5125 2175);
PAINT WHITE (-5125 2175);
DISPLAY INVISIBLE (-5125 2175);
FORCEPROP 2 LAST ROOM PVSA_CPU0_VSENSE_VR
J 0
(-5125 2125);
PAINT ORANGE (-5125 2125);
DISPLAY INVISIBLE (-5125 2125);
FORCEPROP 2 LAST CDS_LIB mstr_discrete
J 0
(-5075 2025);
PAINT ORANGE (-5075 2025);
DISPLAY INVISIBLE (-5075 2025);
FORCEADD OFFPAGE..2
(-3750 1575);
FORCEPROP 2 LAST $XR0 39 
J 0
(-3561 1575);
DISPLAY 0.638298 (-3561 1575);
PAINT MONO (-3561 1575);
FORCEPROP 2 LAST BOM_COST PROC_VRD_VCCIN_CPU0
J 0
(-3550 1625);
PAINT MONO (-3550 1625);
DISPLAY INVISIBLE (-3550 1625);
FORCEPROP 2 LAST PATH I27
J 0
(-3585 1635);
DISPLAY 1.021277 (-3585 1635);
PAINT ORANGE (-3585 1635);
DISPLAY INVISIBLE (-3585 1635);
FORCEPROP 2 LAST CDS_LIB mstr_standard
J 0
(-3750 1575);
PAINT ORANGE (-3750 1575);
DISPLAY INVISIBLE (-3750 1575);
FORCEPROP 2 LAST ROOM PVSA_CPU0_VSENSE_VR
J 0
(-4150 1650);
PAINT ORANGE (-4150 1650);
DISPLAY INVISIBLE (-4150 1650);
FORCEPROP 1 LAST OFFPAGE TRUE
J 0
(-3425 1450);
DISPLAY 0.893617 (-3425 1450);
PAINT GREEN (-3425 1450);
DISPLAY INVISIBLE (-3425 1450);
FORCEPROP 1 LAST COMMENT_BODY TRUE
J 0
(-3795 1480);
DISPLAY 0.893617 (-3795 1480);
PAINT GREEN (-3795 1480);
DISPLAY INVISIBLE (-3795 1480);
FORCEADD GND..1
(-4250 1050);
FORCEPROP 3 LASTPIN (-4250 1100) SIG_NAME GND\g
J 0
(-4240 1110);
DISPLAY 0.659574 (-4240 1110);
PAINT MONO (-4240 1110);
DISPLAY INVISIBLE (-4240 1110);
FORCEPROP 1 LAST PATH I28
J 0
(-4175 1050);
DISPLAY 0.872340 (-4175 1050);
PAINT AQUA (-4175 1050);
DISPLAY INVISIBLE (-4175 1050);
FORCEPROP 2 LAST CDS_LIB mstr_symbols
J 0
(-4250 1050);
PAINT ORANGE (-4250 1050);
DISPLAY INVISIBLE (-4250 1050);
FORCEPROP 1 LAST VOLTAGE 0
J 0
(-4250 1050);
PAINT SKYBLUE (-4250 1050);
DISPLAY INVISIBLE (-4250 1050);
FORCEPROP 2 LAST BOM_COST PROC_VRD_VCCIN_CPU0
J 0
(-4625 1125);
PAINT MONO (-4625 1125);
DISPLAY INVISIBLE (-4625 1125);
FORCEPROP 2 LAST ROOM PVSA_CPU0_VSENSE_VR
J 0
(-4800 1125);
PAINT ORANGE (-4800 1125);
DISPLAY INVISIBLE (-4800 1125);
FORCEPROP 1 LAST SIZE 1B
J 0
(-4175 1000);
DISPLAY 0.893617 (-4175 1000);
PAINT GREEN (-4175 1000);
DISPLAY INVISIBLE (-4175 1000);
FORCEPROP 1 LAST BODY_TYPE PLUMBING
J 0
(-4295 1007);
DISPLAY 0.340426 (-4295 1007);
PAINT GREEN (-4295 1007);
DISPLAY INVISIBLE (-4295 1007);
FORCEPROP 1 LAST HDL_POWER GND
J 0
(-4250 1200);
DISPLAY 0.893617 (-4250 1200);
PAINT GREEN (-4250 1200);
DISPLAY INVISIBLE (-4250 1200);
FORCEADD RES..1
(-5075 1200);
FORCEPROP 1 LAST TOLERANCE 1%
J 0
(-5025 1125);
DISPLAY 0.617021 (-5025 1125);
PAINT SKYBLUE (-5025 1125);
FORCEPROP 1 LASTPIN (-4975 1200) $PN 2
J 0
(-5013 1212);
DISPLAY 0.617021 (-5013 1212);
PAINT ORANGE (-5013 1212);
FORCEPROP 1 LAST PACK_TYPE 0402
J 0
(-5150 1025);
DISPLAY 0.617021 (-5150 1025);
PAINT SKYBLUE (-5150 1025);
FORCEPROP 1 LAST PART_NUMBER G21796-017
J 0
(-5125 1300);
DISPLAY 0.617021 (-5125 1300);
PAINT BLUE (-5125 1300);
FORCEPROP 1 LASTPIN (-5175 1200) $PN 1
J 0
(-5163 1212);
DISPLAY 0.617021 (-5163 1212);
PAINT ORANGE (-5163 1212);
FORCEPROP 1 LAST WATTAGE 1/16W
J 2
(-5075 1075);
DISPLAY 0.617021 (-5075 1075);
PAINT SKYBLUE (-5075 1075);
FORCEPROP 1 LAST VALUE 100.0
J 2
(-5075 1125);
DISPLAY 0.617021 (-5075 1125);
PAINT SKYBLUE (-5075 1125);
FORCEPROP 1 LAST LOCATION R4C1
J 0
(-5125 1250);
DISPLAY 0.617021 (-5125 1250);
PAINT AQUA (-5125 1250);
FORCEPROP 1 LAST MATERIAL CHIP
J 0
(-5050 1075);
DISPLAY 0.638298 (-5050 1075);
PAINT SKYBLUE (-5050 1075);
FORCEPROP 2 LAST SEC_TYPE 0402
J 0
(-5110 1410);
DISPLAY 1.021277 (-5110 1410);
PAINT ORANGE (-5110 1410);
DISPLAY INVISIBLE (-5110 1410);
FORCEPROP 2 LAST SEC 1
J 0
(-5110 1410);
DISPLAY 0.680851 (-5110 1410);
PAINT MONO (-5110 1410);
DISPLAY INVISIBLE (-5110 1410);
FORCEPROP 2 LAST CDS_LIB mstr_discrete
J 0
(-5075 1200);
PAINT ORANGE (-5075 1200);
DISPLAY INVISIBLE (-5075 1200);
FORCEPROP 2 LAST ROOM PVSA_CPU0_VSENSE_VR
J 0
(-5125 1300);
PAINT ORANGE (-5125 1300);
DISPLAY INVISIBLE (-5125 1300);
FORCEPROP 1 LAST PATH I29
J 0
(-5125 1350);
DISPLAY 0.978723 (-5125 1350);
PAINT WHITE (-5125 1350);
DISPLAY INVISIBLE (-5125 1350);
FORCEPROP 2 LAST CDS_LOCATION R4C1
J 0
(-5125 1250);
DISPLAY 0.617021 (-5125 1250);
PAINT AQUA (-5125 1250);
DISPLAY INVISIBLE (-5125 1250);
FORCEPROP 2 LAST BOM_COST PROC_VRD_VCCIN_CPU0
J 0
(-5125 1350);
PAINT MONO (-5125 1350);
DISPLAY INVISIBLE (-5125 1350);
FORCEADD OFFPAGE..2
(-1525 4125);
FORCEPROP 2 LAST $XR0 201 
J 0
(-1336 4125);
DISPLAY 0.638298 (-1336 4125);
PAINT MONO (-1336 4125);
FORCEPROP 2 LAST ROOM PVSA_CPU0_PWR_VR
J 0
(-1925 4200);
DISPLAY 1.936170 (-1925 4200);
PAINT ORANGE (-1925 4200);
DISPLAY INVISIBLE (-1925 4200);
FORCEPROP 2 LAST CDS_LIB mstr_standard
J 0
(-1525 4125);
PAINT ORANGE (-1525 4125);
DISPLAY INVISIBLE (-1525 4125);
FORCEPROP 2 LAST PATH I3
J 0
(-1345 4200);
DISPLAY 1.021277 (-1345 4200);
PAINT ORANGE (-1345 4200);
DISPLAY INVISIBLE (-1345 4200);
FORCEPROP 2 LAST BOM_COST PROC_VRD_VCCIN_CPU0
J 0
(-1325 4175);
DISPLAY 1.446809 (-1325 4175);
PAINT MONO (-1325 4175);
DISPLAY INVISIBLE (-1325 4175);
FORCEPROP 1 LAST OFFPAGE TRUE
J 0
(-1200 4000);
DISPLAY 1.723404 (-1200 4000);
PAINT GREEN (-1200 4000);
DISPLAY INVISIBLE (-1200 4000);
FORCEPROP 1 LAST COMMENT_BODY TRUE
J 0
(-1570 4030);
DISPLAY 1.723404 (-1570 4030);
PAINT GREEN (-1570 4030);
DISPLAY INVISIBLE (-1570 4030);
FORCEADD RES..1
(-5075 1575);
FORCEPROP 1 LASTPIN (-4975 1575) $PN 2
J 0
(-5013 1587);
DISPLAY 0.617021 (-5013 1587);
PAINT ORANGE (-5013 1587);
FORCEPROP 1 LAST PACK_TYPE 0402
J 0
(-5200 1375);
DISPLAY 0.617021 (-5200 1375);
PAINT SKYBLUE (-5200 1375);
FORCEPROP 1 LASTPIN (-5175 1575) $PN 1
J 0
(-5163 1587);
DISPLAY 0.617021 (-5163 1587);
PAINT ORANGE (-5163 1587);
FORCEPROP 1 LAST WATTAGE 1/16W
J 2
(-5100 1425);
DISPLAY 0.617021 (-5100 1425);
PAINT SKYBLUE (-5100 1425);
FORCEPROP 1 LAST PART_NUMBER G21497-005
J 0
(-5200 1675);
DISPLAY 0.617021 (-5200 1675);
PAINT BLUE (-5200 1675);
FORCEPROP 1 LAST LOCATION R4C2
J 0
(-5125 1625);
DISPLAY 0.617021 (-5125 1625);
PAINT AQUA (-5125 1625);
FORCEPROP 1 LAST MATERIAL CHIP
J 0
(-5075 1425);
DISPLAY 0.617021 (-5075 1425);
PAINT SKYBLUE (-5075 1425);
FORCEPROP 1 LAST TOLERANCE 5%
J 0
(-5075 1500);
DISPLAY 0.617021 (-5075 1500);
PAINT SKYBLUE (-5075 1500);
FORCEPROP 1 LAST VALUE 0.0
J 2
(-5100 1500);
DISPLAY 0.617021 (-5100 1500);
PAINT SKYBLUE (-5100 1500);
FORCEPROP 2 LAST SEC_TYPE 0402
J 0
(-5110 1785);
DISPLAY 1.021277 (-5110 1785);
PAINT ORANGE (-5110 1785);
DISPLAY INVISIBLE (-5110 1785);
FORCEPROP 2 LAST SEC 1
J 0
(-5110 1785);
DISPLAY 0.680851 (-5110 1785);
PAINT MONO (-5110 1785);
DISPLAY INVISIBLE (-5110 1785);
FORCEPROP 2 LAST CDS_LIB mstr_discrete
J 0
(-5075 1575);
PAINT ORANGE (-5075 1575);
DISPLAY INVISIBLE (-5075 1575);
FORCEPROP 2 LAST ROOM PVSA_CPU0_VSENSE_VR
J 0
(-5125 1675);
PAINT ORANGE (-5125 1675);
DISPLAY INVISIBLE (-5125 1675);
FORCEPROP 1 LAST PATH I30
J 0
(-5125 1725);
DISPLAY 0.978723 (-5125 1725);
PAINT WHITE (-5125 1725);
DISPLAY INVISIBLE (-5125 1725);
FORCEPROP 2 LAST CDS_LOCATION R4C2
J 0
(-5125 1625);
DISPLAY 0.617021 (-5125 1625);
PAINT AQUA (-5125 1625);
DISPLAY INVISIBLE (-5125 1625);
FORCEPROP 2 LAST BOM_COST PROC_VRD_VCCIN_CPU0
J 0
(-5200 1725);
PAINT MONO (-5200 1725);
DISPLAY INVISIBLE (-5200 1725);
FORCEADD CAP_A..1
(-6250 4200);
FORCEPROP 1 LAST VALUE 0.1UF
J 0
(-6200 4250);
DISPLAY 0.617021 (-6200 4250);
PAINT SKYBLUE (-6200 4250);
FORCEPROP 1 LAST LOCATION C4C10
J 0
(-6200 4300);
DISPLAY 0.617021 (-6200 4300);
PAINT AQUA (-6200 4300);
FORCEPROP 1 LAST PACK_TYPE 0402V
J 0
(-6200 4000);
DISPLAY 0.617021 (-6200 4000);
PAINT SKYBLUE (-6200 4000);
FORCEPROP 1 LASTPIN (-6250 4300) $PN 1
J 0
(-6240 4280);
DISPLAY 0.617021 (-6240 4280);
PAINT ORANGE (-6240 4280);
FORCEPROP 1 LASTPIN (-6250 4100) $PN 2
J 0
(-6240 4080);
DISPLAY 0.617021 (-6240 4080);
PAINT ORANGE (-6240 4080);
FORCEPROP 1 LAST MATERIAL X7R
J 0
(-6200 4100);
DISPLAY 0.617021 (-6200 4100);
PAINT SKYBLUE (-6200 4100);
FORCEPROP 1 LAST TOLERANCE 10%
J 0
(-6200 4150);
DISPLAY 0.617021 (-6200 4150);
PAINT SKYBLUE (-6200 4150);
FORCEPROP 1 LAST VOLTAGE 16V
J 0
(-6200 4200);
DISPLAY 0.617021 (-6200 4200);
PAINT SKYBLUE (-6200 4200);
FORCEPROP 1 LAST PART_NUMBER A36096-030
J 0
(-6200 4050);
DISPLAY 0.617021 (-6200 4050);
PAINT BLUE (-6200 4050);
FORCEPROP 2 LAST SEC 1
J 0
(-6200 4400);
DISPLAY 0.680851 (-6200 4400);
PAINT MONO (-6200 4400);
DISPLAY INVISIBLE (-6200 4400);
FORCEPROP 2 LAST SEC_TYPE 0402V
J 0
(-6200 4400);
DISPLAY 1.021277 (-6200 4400);
PAINT ORANGE (-6200 4400);
DISPLAY INVISIBLE (-6200 4400);
FORCEPROP 2 LAST CDS_SEC 1
J 0
(-6200 4350);
PAINT ORANGE (-6200 4350);
DISPLAY INVISIBLE (-6200 4350);
FORCEPROP 2 LAST CDS_LOCATION C4C10
J 0
(-6200 4300);
DISPLAY 0.617021 (-6200 4300);
PAINT AQUA (-6200 4300);
DISPLAY INVISIBLE (-6200 4300);
FORCEPROP 2 LAST ROOM PVSA_CPU0_PWR_VR
J 0
(-6200 4350);
DISPLAY 1.361702 (-6200 4350);
PAINT ORANGE (-6200 4350);
DISPLAY INVISIBLE (-6200 4350);
FORCEPROP 1 LAST PATH I31
J 0
(-6200 4350);
DISPLAY 0.978723 (-6200 4350);
PAINT WHITE (-6200 4350);
DISPLAY INVISIBLE (-6200 4350);
FORCEPROP 2 LAST CDS_LIB dev_discrete
J 0
(-6250 4200);
PAINT ORANGE (-6250 4200);
DISPLAY INVISIBLE (-6250 4200);
FORCEADD CAP..1
(-6475 4200);
FORCEPROP 1 LAST PART_NUMBER D97712-011
J 0
(-6425 4050);
DISPLAY 0.617021 (-6425 4050);
PAINT BLUE (-6425 4050);
FORCEPROP 1 LAST PACK_TYPE 0402
J 0
(-6425 4000);
DISPLAY 0.617021 (-6425 4000);
PAINT SKYBLUE (-6425 4000);
FORCEPROP 1 LASTPIN (-6475 4100) $PN 2
J 0
(-6465 4080);
DISPLAY 0.617021 (-6465 4080);
PAINT ORANGE (-6465 4080);
FORCEPROP 1 LASTPIN (-6475 4300) $PN 1
J 0
(-6465 4280);
DISPLAY 0.617021 (-6465 4280);
PAINT ORANGE (-6465 4280);
FORCEPROP 1 LAST MATERIAL X6S
J 0
(-6425 4100);
DISPLAY 0.617021 (-6425 4100);
PAINT SKYBLUE (-6425 4100);
FORCEPROP 1 LAST VALUE 1.0UF
J 0
(-6425 4250);
DISPLAY 0.617021 (-6425 4250);
PAINT SKYBLUE (-6425 4250);
FORCEPROP 1 LAST VOLTAGE 16V
J 0
(-6425 4200);
DISPLAY 0.617021 (-6425 4200);
PAINT SKYBLUE (-6425 4200);
FORCEPROP 1 LAST TOLERANCE 10%
J 0
(-6425 4150);
DISPLAY 0.617021 (-6425 4150);
PAINT SKYBLUE (-6425 4150);
FORCEPROP 1 LAST LOCATION C4C9
J 0
(-6425 4300);
DISPLAY 0.617021 (-6425 4300);
PAINT AQUA (-6425 4300);
FORCEPROP 2 LAST CDS_LOCATION C4C9
J 0
(-6425 4300);
DISPLAY 0.617021 (-6425 4300);
PAINT AQUA (-6425 4300);
DISPLAY INVISIBLE (-6425 4300);
FORCEPROP 2 LAST CDS_LIB mstr_discrete
J 0
(-6475 4200);
PAINT ORANGE (-6475 4200);
DISPLAY INVISIBLE (-6475 4200);
FORCEPROP 2 LAST ROOM PVSA_CPU0_PWR_VR
J 0
(-6425 4350);
DISPLAY 1.361702 (-6425 4350);
PAINT ORANGE (-6425 4350);
DISPLAY INVISIBLE (-6425 4350);
FORCEPROP 1 LAST PATH I32
J 0
(-6425 4350);
DISPLAY 0.978723 (-6425 4350);
PAINT WHITE (-6425 4350);
DISPLAY INVISIBLE (-6425 4350);
FORCEPROP 2 LAST SEC 1
J 0
(-6425 4400);
DISPLAY 0.680851 (-6425 4400);
PAINT MONO (-6425 4400);
DISPLAY INVISIBLE (-6425 4400);
FORCEPROP 2 LAST SEC_TYPE 0402
J 0
(-6425 4400);
DISPLAY 1.021277 (-6425 4400);
PAINT ORANGE (-6425 4400);
DISPLAY INVISIBLE (-6425 4400);
FORCEADD CAP..1
(-6700 4200);
FORCEPROP 1 LASTPIN (-6700 4300) $PN 1
J 0
(-6690 4280);
DISPLAY 0.617021 (-6690 4280);
PAINT ORANGE (-6690 4280);
FORCEPROP 1 LASTPIN (-6700 4100) $PN 2
J 0
(-6690 4080);
DISPLAY 0.617021 (-6690 4080);
PAINT ORANGE (-6690 4080);
FORCEPROP 1 LAST MATERIAL X6S
J 0
(-6650 4100);
DISPLAY 0.617021 (-6650 4100);
PAINT SKYBLUE (-6650 4100);
FORCEPROP 1 LAST VOLTAGE 16V
J 0
(-6650 4200);
DISPLAY 0.617021 (-6650 4200);
PAINT SKYBLUE (-6650 4200);
FORCEPROP 1 LAST VALUE 10UF
J 0
(-6650 4250);
DISPLAY 0.617021 (-6650 4250);
PAINT SKYBLUE (-6650 4250);
FORCEPROP 1 LAST TOLERANCE 10%
J 0
(-6650 4150);
DISPLAY 0.617021 (-6650 4150);
PAINT SKYBLUE (-6650 4150);
FORCEPROP 1 LAST PART_NUMBER C95333-007
J 0
(-6650 4050);
DISPLAY 0.617021 (-6650 4050);
PAINT BLUE (-6650 4050);
FORCEPROP 1 LAST LOCATION C6N2
J 0
(-6650 4300);
DISPLAY 0.617021 (-6650 4300);
PAINT AQUA (-6650 4300);
FORCEPROP 1 LAST PACK_TYPE 0805
J 0
(-6650 4000);
DISPLAY 0.617021 (-6650 4000);
PAINT SKYBLUE (-6650 4000);
FORCEPROP 2 LAST CDS_LIB mstr_discrete
J 0
(-6700 4200);
PAINT ORANGE (-6700 4200);
DISPLAY INVISIBLE (-6700 4200);
FORCEPROP 2 LAST CDS_LOCATION C6N2
J 0
(-6650 4300);
DISPLAY 0.617021 (-6650 4300);
PAINT AQUA (-6650 4300);
DISPLAY INVISIBLE (-6650 4300);
FORCEPROP 2 LAST ROOM PVSA_CPU0_PWR_VR
J 0
(-6650 4350);
DISPLAY 1.361702 (-6650 4350);
PAINT ORANGE (-6650 4350);
DISPLAY INVISIBLE (-6650 4350);
FORCEPROP 1 LAST PATH I33
J 0
(-6650 4350);
DISPLAY 0.978723 (-6650 4350);
PAINT WHITE (-6650 4350);
DISPLAY INVISIBLE (-6650 4350);
FORCEPROP 2 LAST SEC 1
J 0
(-6650 4400);
DISPLAY 0.680851 (-6650 4400);
PAINT MONO (-6650 4400);
DISPLAY INVISIBLE (-6650 4400);
FORCEPROP 2 LAST SEC_TYPE 0805
J 0
(-6650 4400);
DISPLAY 1.021277 (-6650 4400);
PAINT ORANGE (-6650 4400);
DISPLAY INVISIBLE (-6650 4400);
FORCEADD CAP..1
(-6925 4200);
FORCEPROP 1 LAST VOLTAGE 16V
J 0
(-6875 4200);
DISPLAY 0.617021 (-6875 4200);
PAINT SKYBLUE (-6875 4200);
FORCEPROP 1 LAST LOCATION C6N3
J 0
(-6875 4300);
DISPLAY 0.617021 (-6875 4300);
PAINT AQUA (-6875 4300);
FORCEPROP 1 LAST TOLERANCE 10%
J 0
(-6875 4150);
DISPLAY 0.617021 (-6875 4150);
PAINT SKYBLUE (-6875 4150);
FORCEPROP 1 LAST VALUE 10UF
J 0
(-6875 4250);
DISPLAY 0.617021 (-6875 4250);
PAINT SKYBLUE (-6875 4250);
FORCEPROP 1 LAST PACK_TYPE 0805
J 0
(-6875 4000);
DISPLAY 0.617021 (-6875 4000);
PAINT SKYBLUE (-6875 4000);
FORCEPROP 1 LASTPIN (-6925 4100) $PN 2
J 0
(-6915 4080);
DISPLAY 0.617021 (-6915 4080);
PAINT ORANGE (-6915 4080);
FORCEPROP 1 LASTPIN (-6925 4300) $PN 1
J 0
(-6915 4280);
DISPLAY 0.617021 (-6915 4280);
PAINT ORANGE (-6915 4280);
FORCEPROP 1 LAST PART_NUMBER C95333-007
J 0
(-6875 4050);
DISPLAY 0.617021 (-6875 4050);
PAINT BLUE (-6875 4050);
FORCEPROP 1 LAST MATERIAL X6S
J 0
(-6875 4100);
DISPLAY 0.617021 (-6875 4100);
PAINT SKYBLUE (-6875 4100);
FORCEPROP 2 LAST CDS_LIB mstr_discrete
J 0
(-6925 4200);
PAINT ORANGE (-6925 4200);
DISPLAY INVISIBLE (-6925 4200);
FORCEPROP 2 LAST CDS_LOCATION C6N3
J 0
(-6875 4300);
DISPLAY 0.617021 (-6875 4300);
PAINT AQUA (-6875 4300);
DISPLAY INVISIBLE (-6875 4300);
FORCEPROP 2 LAST ROOM PVSA_CPU0_PWR_VR
J 0
(-6875 4350);
DISPLAY 1.361702 (-6875 4350);
PAINT ORANGE (-6875 4350);
DISPLAY INVISIBLE (-6875 4350);
FORCEPROP 1 LAST PATH I34
J 0
(-6875 4350);
DISPLAY 0.978723 (-6875 4350);
PAINT WHITE (-6875 4350);
DISPLAY INVISIBLE (-6875 4350);
FORCEPROP 2 LAST SEC 1
J 0
(-6875 4400);
DISPLAY 0.680851 (-6875 4400);
PAINT MONO (-6875 4400);
DISPLAY INVISIBLE (-6875 4400);
FORCEPROP 2 LAST SEC_TYPE 0805
J 0
(-6875 4400);
DISPLAY 1.021277 (-6875 4400);
PAINT ORANGE (-6875 4400);
DISPLAY INVISIBLE (-6875 4400);
FORCEADD CAP..1
(-7175 4200);
FORCEPROP 1 LAST VOLTAGE 16V
J 0
(-7125 4200);
DISPLAY 0.617021 (-7125 4200);
PAINT SKYBLUE (-7125 4200);
FORCEPROP 1 LAST TOLERANCE 10%
J 0
(-7125 4150);
DISPLAY 0.617021 (-7125 4150);
PAINT SKYBLUE (-7125 4150);
FORCEPROP 1 LAST VALUE 10UF
J 0
(-7125 4250);
DISPLAY 0.617021 (-7125 4250);
PAINT SKYBLUE (-7125 4250);
FORCEPROP 1 LAST LOCATION C6N6
J 0
(-7125 4300);
DISPLAY 0.617021 (-7125 4300);
PAINT AQUA (-7125 4300);
FORCEPROP 1 LAST MATERIAL X6S
J 0
(-7125 4100);
DISPLAY 0.617021 (-7125 4100);
PAINT SKYBLUE (-7125 4100);
FORCEPROP 1 LASTPIN (-7175 4300) $PN 1
J 0
(-7165 4280);
DISPLAY 0.617021 (-7165 4280);
PAINT ORANGE (-7165 4280);
FORCEPROP 1 LASTPIN (-7175 4100) $PN 2
J 0
(-7165 4080);
DISPLAY 0.617021 (-7165 4080);
PAINT ORANGE (-7165 4080);
FORCEPROP 1 LAST PART_NUMBER C95333-007
J 0
(-7125 4050);
DISPLAY 0.617021 (-7125 4050);
PAINT BLUE (-7125 4050);
FORCEPROP 1 LAST PACK_TYPE 0805
J 0
(-7125 4000);
DISPLAY 0.617021 (-7125 4000);
PAINT SKYBLUE (-7125 4000);
FORCEPROP 2 LAST CDS_LIB mstr_discrete
J 0
(-7175 4200);
PAINT ORANGE (-7175 4200);
DISPLAY INVISIBLE (-7175 4200);
FORCEPROP 2 LAST ROOM PVSA_CPU0_PWR_VR
J 0
(-7125 4350);
DISPLAY 1.361702 (-7125 4350);
PAINT ORANGE (-7125 4350);
DISPLAY INVISIBLE (-7125 4350);
FORCEPROP 1 LAST PATH I35
J 0
(-7125 4350);
DISPLAY 0.978723 (-7125 4350);
PAINT WHITE (-7125 4350);
DISPLAY INVISIBLE (-7125 4350);
FORCEPROP 2 LAST SEC_TYPE 0805
J 0
(-7125 4400);
DISPLAY 1.021277 (-7125 4400);
PAINT ORANGE (-7125 4400);
DISPLAY INVISIBLE (-7125 4400);
FORCEPROP 2 LAST SEC 1
J 0
(-7125 4400);
DISPLAY 0.680851 (-7125 4400);
PAINT MONO (-7125 4400);
DISPLAY INVISIBLE (-7125 4400);
FORCEPROP 2 LAST CDS_LOCATION C6N6
J 0
(-7125 4300);
DISPLAY 0.617021 (-7125 4300);
PAINT AQUA (-7125 4300);
DISPLAY INVISIBLE (-7125 4300);
FORCEADD VCC_CORE..1
(-7175 4675);
FORCEPROP 3 LASTPIN (-7175 4625) SIG_NAME VR_FET_SW_P12V_STBY_PVCCIN_CPU0\g
J 0
(-7165 4635);
DISPLAY 0.659574 (-7165 4635);
PAINT MONO (-7165 4635);
DISPLAY INVISIBLE (-7165 4635);
FORCEPROP 1 LAST HDL_POWER VR_FET_SW_P12V_STBY_PVCCIN_CPU0
J 1
(-7100 4725);
DISPLAY 0.617021 (-7100 4725);
PAINT GREEN (-7100 4725);
FORCEPROP 1 LAST PATH I36
J 0
(-7125 4700);
DISPLAY 0.872340 (-7125 4700);
PAINT AQUA (-7125 4700);
DISPLAY INVISIBLE (-7125 4700);
FORCEPROP 2 LAST CDS_LIB mstr_symbols
J 0
(-7175 4675);
PAINT ORANGE (-7175 4675);
DISPLAY INVISIBLE (-7175 4675);
FORCEADD RES..2
(-5750 1825);
FORCEPROP 1 LASTPIN (-5750 1725) $PN 2
J 0
(-5745 1735);
DISPLAY 0.617021 (-5745 1735);
PAINT ORANGE (-5745 1735);
FORCEPROP 1 LASTPIN (-5750 1925) $PN 1
J 0
(-5745 1887);
DISPLAY 0.617021 (-5745 1887);
PAINT ORANGE (-5745 1887);
FORCEPROP 1 LAST LOCATION R4C3
J 0
(-5705 1950);
DISPLAY 0.617021 (-5705 1950);
PAINT AQUA (-5705 1950);
FORCEPROP 1 LAST VALUE 1.00K
J 0
(-5705 1900);
DISPLAY 0.617021 (-5705 1900);
PAINT SKYBLUE (-5705 1900);
FORCEPROP 1 LAST TOLERANCE 1%
J 0
(-5705 1850);
DISPLAY 0.617021 (-5705 1850);
PAINT SKYBLUE (-5705 1850);
FORCEPROP 1 LAST WATTAGE 1/16W
J 0
(-5710 1800);
DISPLAY 0.617021 (-5710 1800);
PAINT SKYBLUE (-5710 1800);
FORCEPROP 1 LAST MATERIAL EMPTY
J 0
(-5710 1750);
DISPLAY 0.617021 (-5710 1750);
PAINT RED (-5710 1750);
FORCEPROP 1 LAST PACK_TYPE 0402
J 0
(-5710 1650);
DISPLAY 0.617021 (-5710 1650);
PAINT SKYBLUE (-5710 1650);
FORCEPROP 1 LAST PART_NUMBER G21796-026
J 0
(-5710 1700);
DISPLAY 0.617021 (-5710 1700);
PAINT BLUE (-5710 1700);
FORCEPROP 2 LAST NO_XNET_CONNECTION 1
J 0
(-5700 2050);
PAINT MONO (-5700 2050);
DISPLAY INVISIBLE (-5700 2050);
FORCEPROP 2 LAST SEC 1
J 0
(-5685 2060);
DISPLAY 0.680851 (-5685 2060);
PAINT MONO (-5685 2060);
DISPLAY INVISIBLE (-5685 2060);
FORCEPROP 2 LAST SEC_TYPE 0402
J 0
(-5685 2060);
DISPLAY 1.021277 (-5685 2060);
PAINT ORANGE (-5685 2060);
DISPLAY INVISIBLE (-5685 2060);
FORCEPROP 2 LAST BOM_COST PROC_VRD_VCCIN_CPU0
J 0
(-5700 2000);
PAINT MONO (-5700 2000);
DISPLAY INVISIBLE (-5700 2000);
FORCEPROP 2 LAST CDS_LOCATION R4C3
J 0
(-5705 1950);
DISPLAY 0.617021 (-5705 1950);
PAINT AQUA (-5705 1950);
DISPLAY INVISIBLE (-5705 1950);
FORCEPROP 1 LAST PATH I37
J 0
(-5700 2000);
DISPLAY 0.978723 (-5700 2000);
PAINT WHITE (-5700 2000);
DISPLAY INVISIBLE (-5700 2000);
FORCEPROP 2 LAST ROOM PVSA_CPU0_VSENSE_VR
J 0
(-5700 2000);
PAINT MONO (-5700 2000);
DISPLAY INVISIBLE (-5700 2000);
FORCEPROP 2 LAST CDS_LIB mstr_discrete
J 0
(-5750 1825);
PAINT ORANGE (-5750 1825);
DISPLAY INVISIBLE (-5750 1825);
FORCEADD OFFPAGE..1
(-6450 3825);
FORCEPROP 2 LAST $XR0 201 
J 0
(-6732 3825);
DISPLAY 0.638298 (-6732 3825);
PAINT MONO (-6732 3825);
FORCEPROP 2 LAST ROOM PVSA_CPU0_PWR_VR
J 0
(-6850 3900);
DISPLAY 1.936170 (-6850 3900);
PAINT ORANGE (-6850 3900);
DISPLAY INVISIBLE (-6850 3900);
FORCEPROP 2 LAST BOM_COST PROC_VRD_VCCIN_CPU0
J 0
(-6700 3875);
DISPLAY 1.446809 (-6700 3875);
PAINT MONO (-6700 3875);
DISPLAY INVISIBLE (-6700 3875);
FORCEPROP 2 LAST CDS_LIB mstr_standard
J 0
(-6450 3825);
PAINT ORANGE (-6450 3825);
DISPLAY INVISIBLE (-6450 3825);
FORCEPROP 2 LAST PATH I38
J 0
(-6395 3900);
DISPLAY 1.021277 (-6395 3900);
PAINT ORANGE (-6395 3900);
DISPLAY INVISIBLE (-6395 3900);
FORCEPROP 1 LAST OFFPAGE TRUE
J 0
(-6125 3700);
DISPLAY 1.680851 (-6125 3700);
PAINT GREEN (-6125 3700);
DISPLAY INVISIBLE (-6125 3700);
FORCEPROP 1 LAST COMMENT_BODY TRUE
J 0
(-6325 3725);
DISPLAY 1.680851 (-6325 3725);
PAINT GREEN (-6325 3725);
DISPLAY INVISIBLE (-6325 3725);
FORCEADD GND..1
(-6925 3725);
FORCEPROP 3 LASTPIN (-6925 3775) SIG_NAME GND\g
J 0
(-6915 3785);
DISPLAY 0.659574 (-6915 3785);
PAINT MONO (-6915 3785);
DISPLAY INVISIBLE (-6915 3785);
FORCEPROP 2 LAST ROOM PVSA_CPU0_PWR_VR
J 0
(-7475 3800);
DISPLAY 1.936170 (-7475 3800);
PAINT ORANGE (-7475 3800);
DISPLAY INVISIBLE (-7475 3800);
FORCEPROP 2 LAST BOM_COST PROC_VRD_VCCIN_CPU0
J 0
(-7300 3800);
DISPLAY 1.446809 (-7300 3800);
PAINT MONO (-7300 3800);
DISPLAY INVISIBLE (-7300 3800);
FORCEPROP 1 LAST SIZE 1B
J 0
(-6850 3675);
DISPLAY 1.723404 (-6850 3675);
PAINT GREEN (-6850 3675);
DISPLAY INVISIBLE (-6850 3675);
FORCEPROP 1 LAST PATH I39
J 0
(-6850 3725);
DISPLAY 0.872340 (-6850 3725);
PAINT AQUA (-6850 3725);
DISPLAY INVISIBLE (-6850 3725);
FORCEPROP 2 LAST CDS_LIB mstr_symbols
J 0
(-6925 3725);
PAINT ORANGE (-6925 3725);
DISPLAY INVISIBLE (-6925 3725);
FORCEPROP 1 LAST VOLTAGE 0
J 0
(-6925 3725);
PAINT SKYBLUE (-6925 3725);
DISPLAY INVISIBLE (-6925 3725);
FORCEPROP 1 LAST BODY_TYPE PLUMBING
J 0
(-6970 3682);
DISPLAY 0.340426 (-6970 3682);
PAINT GREEN (-6970 3682);
DISPLAY INVISIBLE (-6970 3682);
FORCEPROP 1 LAST HDL_POWER GND
J 0
(-6925 3875);
DISPLAY 1.723404 (-6925 3875);
PAINT GREEN (-6925 3875);
DISPLAY INVISIBLE (-6925 3875);
FORCEADD PVSA_CPU0..1
(-275 3725);
FORCEPROP 3 LASTPIN (-275 3675) SIG_NAME PVSA_CPU0\g
J 0
(-265 3685);
DISPLAY 0.659574 (-265 3685);
PAINT MONO (-265 3685);
DISPLAY INVISIBLE (-265 3685);
FORCEPROP 1 LAST VOLTAGE 1.1V
J 0
(-320 3682);
DISPLAY 0.340426 (-320 3682);
PAINT SKYBLUE (-320 3682);
DISPLAY INVISIBLE (-320 3682);
FORCEPROP 2 LAST CDS_LIB mstr_symbols
J 0
(-275 3725);
PAINT ORANGE (-275 3725);
DISPLAY INVISIBLE (-275 3725);
FORCEPROP 1 LAST PATH I4
J 0
(-225 3750);
DISPLAY 0.872340 (-225 3750);
PAINT AQUA (-225 3750);
DISPLAY INVISIBLE (-225 3750);
FORCEPROP 1 LAST BODY_TYPE PLUMBING
J 0
(-320 3682);
DISPLAY 0.340426 (-320 3682);
PAINT GREEN (-320 3682);
DISPLAY INVISIBLE (-320 3682);
FORCEPROP 1 LAST HDL_POWER PVSA_CPU0
J 1
(-275 3775);
DISPLAY 0.872340 (-275 3775);
PAINT GREEN (-275 3775);
DISPLAY INVISIBLE (-275 3775);
FORCEADD OFFPAGE..1
(-7200 2075);
FORCEPROP 2 LAST $XR0 201 
J 0
(-7452 2075);
DISPLAY 0.638298 (-7452 2075);
PAINT MONO (-7452 2075);
FORCEPROP 2 LAST PATH I40
J 0
(-7135 2135);
DISPLAY 1.021277 (-7135 2135);
PAINT ORANGE (-7135 2135);
DISPLAY INVISIBLE (-7135 2135);
FORCEPROP 2 LAST CDS_LIB mstr_standard
J 0
(-7200 2075);
PAINT ORANGE (-7200 2075);
DISPLAY INVISIBLE (-7200 2075);
FORCEPROP 2 LAST BOM_COST PROC_VRD_VCCIN_CPU0
J 0
(-7400 2125);
PAINT MONO (-7400 2125);
DISPLAY INVISIBLE (-7400 2125);
FORCEPROP 2 LAST ROOM PVSA_CPU0_VSENSE_VR
J 0
(-7725 2150);
PAINT ORANGE (-7725 2150);
DISPLAY INVISIBLE (-7725 2150);
FORCEPROP 1 LAST OFFPAGE TRUE
J 0
(-6875 1950);
DISPLAY 0.893617 (-6875 1950);
PAINT GREEN (-6875 1950);
DISPLAY INVISIBLE (-6875 1950);
FORCEPROP 1 LAST COMMENT_BODY TRUE
J 0
(-7075 1975);
DISPLAY 0.893617 (-7075 1975);
PAINT GREEN (-7075 1975);
DISPLAY INVISIBLE (-7075 1975);
FORCEADD OFFPAGE..1
(-7225 1600);
FORCEPROP 2 LAST $XR0 201 
J 0
(-7477 1600);
DISPLAY 0.638298 (-7477 1600);
PAINT MONO (-7477 1600);
FORCEPROP 2 LAST PATH I41
J 0
(-7160 1660);
DISPLAY 1.021277 (-7160 1660);
PAINT ORANGE (-7160 1660);
DISPLAY INVISIBLE (-7160 1660);
FORCEPROP 2 LAST CDS_LIB mstr_standard
J 0
(-7225 1600);
PAINT ORANGE (-7225 1600);
DISPLAY INVISIBLE (-7225 1600);
FORCEPROP 2 LAST BOM_COST PROC_VRD_VCCIN_CPU0
J 0
(-7425 1650);
PAINT MONO (-7425 1650);
DISPLAY INVISIBLE (-7425 1650);
FORCEPROP 2 LAST ROOM PVSA_CPU0_VSENSE_VR
J 0
(-7750 1675);
PAINT ORANGE (-7750 1675);
DISPLAY INVISIBLE (-7750 1675);
FORCEPROP 1 LAST OFFPAGE TRUE
J 0
(-6900 1475);
DISPLAY 0.893617 (-6900 1475);
PAINT GREEN (-6900 1475);
DISPLAY INVISIBLE (-6900 1475);
FORCEPROP 1 LAST COMMENT_BODY TRUE
J 0
(-7100 1500);
DISPLAY 0.893617 (-7100 1500);
PAINT GREEN (-7100 1500);
DISPLAY INVISIBLE (-7100 1500);
FORCEADD P5V_STBY..1
(-4550 4850);
FORCEPROP 3 LASTPIN (-4550 4800) SIG_NAME P5V_STBY\g
J 0
(-4540 4810);
DISPLAY 0.659574 (-4540 4810);
PAINT MONO (-4540 4810);
DISPLAY INVISIBLE (-4540 4810);
FORCEPROP 1 LAST VOLTAGE 5.0V
J 0
(-4595 4807);
DISPLAY 0.340426 (-4595 4807);
PAINT SKYBLUE (-4595 4807);
DISPLAY INVISIBLE (-4595 4807);
FORCEPROP 1 LAST SIZE 1B
J 0
(-4505 4872);
DISPLAY 0.340426 (-4505 4872);
PAINT GREEN (-4505 4872);
DISPLAY INVISIBLE (-4505 4872);
FORCEPROP 2 LAST CDS_LIB mstr_symbols
J 0
(-4550 4850);
PAINT ORANGE (-4550 4850);
DISPLAY INVISIBLE (-4550 4850);
FORCEPROP 1 LAST PATH I42
J 0
(-4505 4852);
DISPLAY 0.340426 (-4505 4852);
PAINT GREEN (-4505 4852);
DISPLAY INVISIBLE (-4505 4852);
FORCEPROP 1 LAST BODY_TYPE PLUMBING
J 0
(-4595 4807);
DISPLAY 0.340426 (-4595 4807);
PAINT GREEN (-4595 4807);
DISPLAY INVISIBLE (-4595 4807);
FORCEPROP 1 LAST HDL_POWER P5V_STBY
J 0
(-4850 4725);
DISPLAY 0.872340 (-4850 4725);
PAINT ORANGE (-4850 4725);
DISPLAY INVISIBLE (-4850 4725);
FORCEADD CAP_A..1
(-600 3075);
FORCEPROP 1 LAST LOCATION C4C11
J 0
(-550 3175);
DISPLAY 0.617021 (-550 3175);
PAINT AQUA (-550 3175);
FORCEPROP 1 LASTPIN (-600 2975) $PN 2
J 0
(-590 2955);
DISPLAY 0.617021 (-590 2955);
PAINT ORANGE (-590 2955);
FORCEPROP 1 LASTPIN (-600 3175) $PN 1
J 0
(-590 3155);
DISPLAY 0.617021 (-590 3155);
PAINT ORANGE (-590 3155);
FORCEPROP 1 LAST VALUE 22.0UF
J 0
(-550 3125);
DISPLAY 0.617021 (-550 3125);
PAINT SKYBLUE (-550 3125);
FORCEPROP 1 LAST VOLTAGE 4V
J 0
(-550 3075);
DISPLAY 0.617021 (-550 3075);
PAINT SKYBLUE (-550 3075);
FORCEPROP 1 LAST TOLERANCE 20%
J 0
(-550 3025);
DISPLAY 0.617021 (-550 3025);
PAINT SKYBLUE (-550 3025);
FORCEPROP 1 LAST MATERIAL X6S
J 0
(-550 2975);
DISPLAY 0.617021 (-550 2975);
PAINT SKYBLUE (-550 2975);
FORCEPROP 1 LAST PART_NUMBER E15431-004
J 0
(-550 2925);
DISPLAY 0.617021 (-550 2925);
PAINT BLUE (-550 2925);
FORCEPROP 1 LAST PACK_TYPE 0603V
J 0
(-550 2875);
DISPLAY 0.617021 (-550 2875);
PAINT SKYBLUE (-550 2875);
FORCEPROP 2 LAST CDS_LOCATION C4C11
J 0
(-550 3175);
DISPLAY 0.617021 (-550 3175);
PAINT AQUA (-550 3175);
DISPLAY INVISIBLE (-550 3175);
FORCEPROP 2 LAST CDS_LIB dev_discrete
J 0
(-600 3075);
PAINT ORANGE (-600 3075);
DISPLAY INVISIBLE (-600 3075);
FORCEPROP 2 LAST CDS_SEC 1
J 0
(-550 3225);
PAINT ORANGE (-550 3225);
DISPLAY INVISIBLE (-550 3225);
FORCEPROP 1 LAST PATH I43
J 0
(-550 3225);
DISPLAY 0.978723 (-550 3225);
PAINT WHITE (-550 3225);
DISPLAY INVISIBLE (-550 3225);
FORCEPROP 2 LAST SEC_TYPE 0603V
J 0
(-550 3275);
DISPLAY 1.021277 (-550 3275);
PAINT ORANGE (-550 3275);
DISPLAY INVISIBLE (-550 3275);
FORCEPROP 2 LAST SEC 1
J 0
(-550 3275);
DISPLAY 0.680851 (-550 3275);
PAINT MONO (-550 3275);
DISPLAY INVISIBLE (-550 3275);
FORCEADD RES..2
(-275 3075);
FORCEPROP 1 LASTPIN (-275 3175) $PN 1
J 0
(-270 3137);
DISPLAY 0.787234 (-270 3137);
PAINT ORANGE (-270 3137);
FORCEPROP 1 LASTPIN (-275 2975) $PN 2
J 0
(-270 2985);
DISPLAY 0.787234 (-270 2985);
PAINT ORANGE (-270 2985);
FORCEPROP 1 LAST LOCATION R6N4
J 0
(-230 3200);
DISPLAY 0.617021 (-230 3200);
PAINT AQUA (-230 3200);
FORCEPROP 1 LAST VALUE 51.1
J 0
(-230 3150);
DISPLAY 0.617021 (-230 3150);
PAINT SKYBLUE (-230 3150);
FORCEPROP 1 LAST TOLERANCE 1.0%
J 0
(-230 3100);
DISPLAY 0.617021 (-230 3100);
PAINT SKYBLUE (-230 3100);
FORCEPROP 1 LAST WATTAGE 1/16W
J 0
(-235 3050);
DISPLAY 0.617021 (-235 3050);
PAINT SKYBLUE (-235 3050);
FORCEPROP 1 LAST MATERIAL CHIP
J 0
(-235 3000);
DISPLAY 0.617021 (-235 3000);
PAINT SKYBLUE (-235 3000);
FORCEPROP 1 LAST PART_NUMBER G21796-208
J 0
(-235 2950);
DISPLAY 0.617021 (-235 2950);
PAINT BLUE (-235 2950);
FORCEPROP 1 LAST PACK_TYPE 0402
J 0
(-235 2900);
DISPLAY 0.617021 (-235 2900);
PAINT SKYBLUE (-235 2900);
FORCEPROP 2 LAST CDS_LOCATION R6N4
J 0
(-230 3200);
DISPLAY 0.617021 (-230 3200);
PAINT AQUA (-230 3200);
DISPLAY INVISIBLE (-230 3200);
FORCEPROP 2 LAST CDS_LIB mstr_discrete
J 0
(-275 3075);
PAINT ORANGE (-275 3075);
DISPLAY INVISIBLE (-275 3075);
FORCEPROP 1 LAST PATH I45
J 0
(-225 3250);
DISPLAY 0.978723 (-225 3250);
PAINT WHITE (-225 3250);
DISPLAY INVISIBLE (-225 3250);
FORCEPROP 2 LAST SEC 1
J 0
(-225 3300);
DISPLAY 0.680851 (-225 3300);
PAINT MONO (-225 3300);
DISPLAY INVISIBLE (-225 3300);
FORCEPROP 2 LAST SEC_TYPE 0402
J 0
(-225 3300);
DISPLAY 1.021277 (-225 3300);
PAINT ORANGE (-225 3300);
DISPLAY INVISIBLE (-225 3300);
FORCEADD IR354XX..1
(-3150 3925);
FORCEPROP 2 LASTPIN (-3650 3825) $PN 34
J 2
(-3660 3835);
DISPLAY 0.617021 (-3660 3835);
PAINT MONO (-3660 3835);
FORCEPROP 2 LASTPIN (-3650 3975) $PN 41
J 2
(-3660 3985);
DISPLAY 0.617021 (-3660 3985);
PAINT MONO (-3660 3985);
FORCEPROP 2 LASTPIN (-3650 3925) $PN 6
J 2
(-3660 3935);
DISPLAY 0.617021 (-3660 3935);
PAINT MONO (-3660 3935);
FORCEPROP 2 LASTPIN (-3650 4075) $PN 1
J 2
(-3660 4085);
DISPLAY 0.617021 (-3660 4085);
PAINT MONO (-3660 4085);
FORCEPROP 2 LASTPIN (-2650 3375) $PN 5
J 0
(-2640 3385);
DISPLAY 0.617021 (-2640 3385);
PAINT MONO (-2640 3385);
FORCEPROP 2 LASTPIN (-3650 4475) $PN 3
J 2
(-3660 4485);
DISPLAY 0.617021 (-3660 4485);
PAINT MONO (-3660 4485);
FORCEPROP 2 LASTPIN (-3650 4375) $PN 25
J 2
(-3660 4385);
DISPLAY 0.617021 (-3660 4385);
PAINT MONO (-3660 4385);
FORCEPROP 2 LASTPIN (-3650 4425) $PN 30
J 2
(-3660 4435);
DISPLAY 0.617021 (-3660 4435);
PAINT MONO (-3660 4435);
FORCEPROP 2 LASTPIN (-2650 4475) $PN 38
J 0
(-2640 4485);
DISPLAY 0.617021 (-2640 4485);
PAINT MONO (-2640 4485);
FORCEPROP 2 LASTPIN (-2650 4225) $PN 31
J 0
(-2640 4235);
DISPLAY 0.617021 (-2640 4235);
PAINT MONO (-2640 4235);
FORCEPROP 2 LASTPIN (-3650 4275) $PN 4
J 2
(-3660 4285);
DISPLAY 0.617021 (-3660 4285);
PAINT MONO (-3660 4285);
FORCEPROP 1 LAST PART_NUMBER H73684-001
J 0
(-3600 3225);
DISPLAY 0.617021 (-3600 3225);
PAINT BLUE (-3600 3225);
FORCEPROP 2 LASTPIN (-2650 3425) $PN 7
J 0
(-2640 3435);
DISPLAY 0.617021 (-2640 3435);
PAINT MONO (-2640 3435);
FORCEPROP 1 LAST LOCATION EU4C1
J 0
(-3600 4725);
DISPLAY 0.617021 (-3600 4725);
PAINT AQUA (-3600 4725);
FORCEPROP 2 LASTPIN (-2650 4275) $PN 37
J 0
(-2640 4285);
DISPLAY 0.617021 (-2640 4285);
PAINT MONO (-2640 4285);
FORCEPROP 2 LASTPIN (-2650 3975) $PN 36
J 0
(-2640 3985);
DISPLAY 0.617021 (-2640 3985);
PAINT MONO (-2640 3985);
FORCEPROP 2 LASTPIN (-2650 3625) $PN 10
J 0
(-2640 3635);
DISPLAY 0.617021 (-2640 3635);
PAINT MONO (-2640 3635);
FORCEPROP 1 LAST MATERIAL IC
J 0
(-3600 4675);
DISPLAY 0.617021 (-3600 4675);
PAINT SKYBLUE (-3600 4675);
FORCEPROP 2 LASTPIN (-2650 3475) $PN 40
J 0
(-2640 3485);
DISPLAY 0.617021 (-2640 3485);
PAINT MONO (-2640 3485);
FORCEPROP 2 LASTPIN (-2650 3525) $PN 2
J 0
(-2640 3535);
DISPLAY 0.617021 (-2640 3535);
PAINT MONO (-2640 3535);
FORCEPROP 2 LASTPIN (-3650 3725) $PN 39
J 2
(-3660 3735);
DISPLAY 0.617021 (-3660 3735);
PAINT MONO (-3660 3735);
FORCEPROP 2 LASTPIN (-3650 3625) $PN 33
J 2
(-3660 3635);
DISPLAY 0.617021 (-3660 3635);
PAINT MONO (-3660 3635);
FORCEPROP 2 LASTPIN (-3650 3575) $PN 32
J 2
(-3660 3585);
DISPLAY 0.617021 (-3660 3585);
PAINT MONO (-3660 3585);
FORCEPROP 2 LASTPIN (-3650 4175) $PN 35
J 2
(-3660 4185);
DISPLAY 0.617021 (-3660 4185);
PAINT MONO (-3660 4185);
FORCEPROP 2 LAST CDS_LIB mstr_discrete
J 0
(-3150 3925);
PAINT ORANGE (-3150 3925);
DISPLAY INVISIBLE (-3150 3925);
FORCEPROP 2 LAST CDS_LOCATION EU4C1
J 0
(-3600 4725);
PAINT GREEN (-3600 4725);
DISPLAY INVISIBLE (-3600 4725);
FORCEPROP 2 LAST CDS_SEC 1
J 0
(-3600 4775);
PAINT MONO (-3600 4775);
DISPLAY INVISIBLE (-3600 4775);
FORCEPROP 2 LAST $SEC 1
J 0
(-3600 4775);
PAINT MONO (-3600 4775);
DISPLAY INVISIBLE (-3600 4775);
FORCEPROP 1 LAST PACK_TYPE SM
J 0
(-3600 4775);
PAINT SKYBLUE (-3600 4775);
DISPLAY INVISIBLE (-3600 4775);
FORCEPROP 1 LAST PATH I46
J 0
(-3150 4675);
PAINT GREEN (-3150 4675);
DISPLAY INVISIBLE (-3150 4675);
FORCEPROP 1 LAST VALUE IR35412
J 1
(-3150 4550);
DISPLAY 0.617021 (-3150 4550);
PAINT SKYBLUE (-3150 4550);
DISPLAY INVISIBLE (-3150 4550);
FORCEADD CAP_A..1
(-950 3075);
FORCEPROP 1 LASTPIN (-950 3175) $PN 1
J 0
(-940 3155);
DISPLAY 0.617021 (-940 3155);
PAINT ORANGE (-940 3155);
FORCEPROP 1 LAST LOCATION C6N7
J 0
(-900 3175);
DISPLAY 0.617021 (-900 3175);
PAINT AQUA (-900 3175);
FORCEPROP 1 LAST MATERIAL X6S
J 0
(-900 2975);
DISPLAY 0.617021 (-900 2975);
PAINT SKYBLUE (-900 2975);
FORCEPROP 1 LAST PACK_TYPE 0603V
J 0
(-900 2875);
DISPLAY 0.617021 (-900 2875);
PAINT SKYBLUE (-900 2875);
FORCEPROP 1 LASTPIN (-950 2975) $PN 2
J 0
(-940 2955);
DISPLAY 0.617021 (-940 2955);
PAINT ORANGE (-940 2955);
FORCEPROP 1 LAST VALUE 22.0UF
J 0
(-900 3125);
DISPLAY 0.617021 (-900 3125);
PAINT SKYBLUE (-900 3125);
FORCEPROP 1 LAST VOLTAGE 4V
J 0
(-900 3075);
DISPLAY 0.617021 (-900 3075);
PAINT SKYBLUE (-900 3075);
FORCEPROP 1 LAST TOLERANCE 20%
J 0
(-900 3025);
DISPLAY 0.617021 (-900 3025);
PAINT SKYBLUE (-900 3025);
FORCEPROP 1 LAST PART_NUMBER E15431-004
J 0
(-900 2925);
DISPLAY 0.617021 (-900 2925);
PAINT BLUE (-900 2925);
FORCEPROP 2 LAST CDS_LIB dev_discrete
J 0
(-950 3075);
PAINT ORANGE (-950 3075);
DISPLAY INVISIBLE (-950 3075);
FORCEPROP 2 LAST CDS_LOCATION C6N7
J 0
(-900 3175);
DISPLAY 0.617021 (-900 3175);
PAINT AQUA (-900 3175);
DISPLAY INVISIBLE (-900 3175);
FORCEPROP 2 LAST CDS_SEC 1
J 0
(-900 3225);
PAINT ORANGE (-900 3225);
DISPLAY INVISIBLE (-900 3225);
FORCEPROP 1 LAST PATH I5
J 0
(-900 3225);
DISPLAY 0.978723 (-900 3225);
PAINT WHITE (-900 3225);
DISPLAY INVISIBLE (-900 3225);
FORCEPROP 2 LAST ROOM PVSA_CPU0_PWR_VR
J 0
(-900 3225);
DISPLAY 1.446809 (-900 3225);
PAINT MONO (-900 3225);
DISPLAY INVISIBLE (-900 3225);
FORCEPROP 2 LAST BOM_COST PROC_VRD_VCCIN_CPU0
J 0
(-900 3225);
DISPLAY 1.446809 (-900 3225);
PAINT MONO (-900 3225);
DISPLAY INVISIBLE (-900 3225);
FORCEPROP 2 LAST SEC_TYPE 0603V
J 0
(-895 3275);
DISPLAY 1.021277 (-895 3275);
PAINT ORANGE (-895 3275);
DISPLAY INVISIBLE (-895 3275);
FORCEPROP 2 LAST SEC 1
J 0
(-895 3275);
DISPLAY 0.680851 (-895 3275);
PAINT MONO (-895 3275);
DISPLAY INVISIBLE (-895 3275);
FORCEADD GND..1
(-275 2725);
FORCEPROP 3 LASTPIN (-275 2775) SIG_NAME GND\g
J 0
(-265 2785);
DISPLAY 0.659574 (-265 2785);
PAINT MONO (-265 2785);
DISPLAY INVISIBLE (-265 2785);
FORCEPROP 2 LAST ROOM PVSA_CPU0_PWR_VR
J 0
(-825 2800);
DISPLAY 1.936170 (-825 2800);
PAINT ORANGE (-825 2800);
DISPLAY INVISIBLE (-825 2800);
FORCEPROP 1 LAST SIZE 1B
J 0
(-200 2675);
DISPLAY 1.723404 (-200 2675);
PAINT GREEN (-200 2675);
DISPLAY INVISIBLE (-200 2675);
FORCEPROP 1 LAST PATH I6
J 0
(-200 2725);
DISPLAY 0.872340 (-200 2725);
PAINT AQUA (-200 2725);
DISPLAY INVISIBLE (-200 2725);
FORCEPROP 2 LAST CDS_LIB mstr_symbols
J 0
(-275 2725);
PAINT ORANGE (-275 2725);
DISPLAY INVISIBLE (-275 2725);
FORCEPROP 1 LAST VOLTAGE 0
J 0
(-275 2725);
PAINT SKYBLUE (-275 2725);
DISPLAY INVISIBLE (-275 2725);
FORCEPROP 2 LAST BOM_COST PROC_VRD_VCCIN_CPU0
J 0
(-650 2800);
DISPLAY 1.446809 (-650 2800);
PAINT MONO (-650 2800);
DISPLAY INVISIBLE (-650 2800);
FORCEPROP 1 LAST BODY_TYPE PLUMBING
J 0
(-320 2682);
DISPLAY 0.340426 (-320 2682);
PAINT GREEN (-320 2682);
DISPLAY INVISIBLE (-320 2682);
FORCEPROP 1 LAST HDL_POWER GND
J 0
(-275 2875);
DISPLAY 1.723404 (-275 2875);
PAINT GREEN (-275 2875);
DISPLAY INVISIBLE (-275 2875);
FORCEADD RES..2
(-775 4100);
FORCEPROP 1 LASTPIN (-775 4200) $PN 1
J 0
(-770 4162);
DISPLAY 0.617021 (-770 4162);
PAINT ORANGE (-770 4162);
FORCEPROP 1 LASTPIN (-775 4000) $PN 2
J 0
(-770 4010);
DISPLAY 0.617021 (-770 4010);
PAINT ORANGE (-770 4010);
FORCEPROP 1 LAST PACK_TYPE 0402
J 0
(-735 3925);
DISPLAY 0.617021 (-735 3925);
PAINT SKYBLUE (-735 3925);
FORCEPROP 1 LAST LOCATION R4C13
J 0
(-730 4225);
DISPLAY 0.617021 (-730 4225);
PAINT AQUA (-730 4225);
FORCEPROP 1 LAST VALUE 68.1K
J 0
(-730 4175);
DISPLAY 0.617021 (-730 4175);
PAINT SKYBLUE (-730 4175);
FORCEPROP 1 LAST TOLERANCE 1%
J 0
(-730 4125);
DISPLAY 0.617021 (-730 4125);
PAINT SKYBLUE (-730 4125);
FORCEPROP 1 LAST WATTAGE 1/16W
J 0
(-735 4075);
DISPLAY 0.617021 (-735 4075);
PAINT SKYBLUE (-735 4075);
FORCEPROP 1 LAST MATERIAL EMPTY
J 0
(-735 4025);
DISPLAY 0.617021 (-735 4025);
PAINT RED (-735 4025);
FORCEPROP 1 LAST PART_NUMBER G21796-187
J 0
(-735 3975);
DISPLAY 0.617021 (-735 3975);
PAINT BLUE (-735 3975);
FORCEPROP 2 LAST CDS_LIB mstr_discrete
J 0
(-775 4100);
PAINT ORANGE (-775 4100);
DISPLAY INVISIBLE (-775 4100);
FORCEPROP 1 LAST PATH I62
J 0
(-725 4275);
DISPLAY 0.978723 (-725 4275);
PAINT WHITE (-725 4275);
DISPLAY INVISIBLE (-725 4275);
FORCEPROP 2 LAST CDS_SEC 1
J 0
(-725 4325);
PAINT MONO (-725 4325);
DISPLAY INVISIBLE (-725 4325);
FORCEPROP 2 LAST $SEC 1
J 0
(-725 4325);
PAINT MONO (-725 4325);
DISPLAY INVISIBLE (-725 4325);
FORCEADD GND..1
(-775 3825);
FORCEPROP 3 LASTPIN (-775 3875) SIG_NAME GND\g
J 0
(-765 3885);
DISPLAY 0.659574 (-765 3885);
PAINT MONO (-765 3885);
DISPLAY INVISIBLE (-765 3885);
FORCEPROP 2 LAST ROOM PVSA_CPU1_PWR_VR
J 0
(-1325 3900);
DISPLAY 1.936170 (-1325 3900);
PAINT ORANGE (-1325 3900);
DISPLAY INVISIBLE (-1325 3900);
FORCEPROP 1 LAST SIZE 1B
J 0
(-700 3775);
DISPLAY 1.723404 (-700 3775);
PAINT GREEN (-700 3775);
DISPLAY INVISIBLE (-700 3775);
FORCEPROP 2 LAST BOM_COST PROC_VRD_VCCIN_CPU0
J 0
(-1150 3900);
DISPLAY 1.446809 (-1150 3900);
PAINT MONO (-1150 3900);
DISPLAY INVISIBLE (-1150 3900);
FORCEPROP 1 LAST PATH I63
J 0
(-700 3825);
DISPLAY 0.872340 (-700 3825);
PAINT AQUA (-700 3825);
DISPLAY INVISIBLE (-700 3825);
FORCEPROP 2 LAST CDS_LIB mstr_symbols
J 0
(-775 3825);
PAINT ORANGE (-775 3825);
DISPLAY INVISIBLE (-775 3825);
FORCEPROP 1 LAST VOLTAGE 0
J 0
(-775 3825);
PAINT SKYBLUE (-775 3825);
DISPLAY INVISIBLE (-775 3825);
FORCEPROP 1 LAST BODY_TYPE PLUMBING
J 0
(-820 3782);
DISPLAY 0.340426 (-820 3782);
PAINT GREEN (-820 3782);
DISPLAY INVISIBLE (-820 3782);
FORCEPROP 1 LAST HDL_POWER GND
J 0
(-775 3975);
DISPLAY 1.723404 (-775 3975);
PAINT GREEN (-775 3975);
DISPLAY INVISIBLE (-775 3975);
FORCEADD CAP..1
(-2025 3950);
FORCEPROP 1 LASTPIN (-2025 4050) $PN 1
J 0
(-2015 4030);
DISPLAY 0.787234 (-2015 4030);
PAINT ORANGE (-2015 4030);
FORCEPROP 1 LASTPIN (-2025 3850) $PN 2
J 0
(-2015 3830);
DISPLAY 0.787234 (-2015 3830);
PAINT ORANGE (-2015 3830);
FORCEPROP 1 LAST LOCATION CT58
J 0
(-2175 3950);
DISPLAY 0.617021 (-2175 3950);
PAINT AQUA (-2175 3950);
FORCEPROP 1 LAST VALUE 1000PF
J 0
(-1975 4000);
DISPLAY 0.617021 (-1975 4000);
PAINT SKYBLUE (-1975 4000);
FORCEPROP 1 LAST VOLTAGE 50V
J 0
(-1975 3950);
DISPLAY 0.617021 (-1975 3950);
PAINT SKYBLUE (-1975 3950);
FORCEPROP 1 LAST TOLERANCE 10%
J 0
(-1975 3900);
DISPLAY 0.617021 (-1975 3900);
PAINT SKYBLUE (-1975 3900);
FORCEPROP 1 LAST MATERIAL X7R
J 0
(-1975 3850);
DISPLAY 0.617021 (-1975 3850);
PAINT SKYBLUE (-1975 3850);
FORCEPROP 1 LAST PART_NUMBER A36096-046
J 0
(-1975 3800);
DISPLAY 0.617021 (-1975 3800);
PAINT BLUE (-1975 3800);
FORCEPROP 1 LAST PACK_TYPE 0402LF
J 0
(-1975 3750);
DISPLAY 0.617021 (-1975 3750);
PAINT SKYBLUE (-1975 3750);
FORCEPROP 0 LAST POP NOPOP
J 0
(-1950 4050);
DISPLAY 1.021277 (-1950 4050);
PAINT RED (-1950 4050);
FORCEPROP 0 LAST ROOM VDDQ_KLM_PWR_VR
J 0
(-1975 4150);
DISPLAY 1.021277 (-1975 4150);
PAINT ORANGE (-1975 4150);
DISPLAY INVISIBLE (-1975 4150);
FORCEPROP 1 LAST PATH I65
J 0
(-1975 4100);
DISPLAY 0.978723 (-1975 4100);
PAINT WHITE (-1975 4100);
DISPLAY INVISIBLE (-1975 4100);
FORCEPROP 2 LAST CDS_LIB mstr_discrete
J 0
(-2025 3950);
PAINT MONO (-2025 3950);
DISPLAY INVISIBLE (-2025 3950);
FORCEPROP 0 LAST SEC 1
J 0
(-2000 4075);
DISPLAY 0.680851 (-2000 4075);
PAINT MONO (-2000 4075);
DISPLAY INVISIBLE (-2000 4075);
FORCEPROP 2 LAST SEC_TYPE 0402LF
J 0
(-1975 4150);
DISPLAY 1.021277 (-1975 4150);
PAINT ORANGE (-1975 4150);
DISPLAY INVISIBLE (-1975 4150);
FORCEADD GND..1
(-2025 3750);
FORCEPROP 3 LASTPIN (-2025 3800) SIG_NAME GND\g
J 0
(-2015 3810);
DISPLAY 0.659574 (-2015 3810);
PAINT MONO (-2015 3810);
DISPLAY INVISIBLE (-2015 3810);
FORCEPROP 2 LAST ROOM VDDQ_KLM_PWR_VR
J 0
(-2600 3825);
DISPLAY 1.361702 (-2600 3825);
PAINT ORANGE (-2600 3825);
DISPLAY INVISIBLE (-2600 3825);
FORCEPROP 1 LAST VOLTAGE 0
J 0
(-2025 3750);
PAINT SKYBLUE (-2025 3750);
DISPLAY INVISIBLE (-2025 3750);
FORCEPROP 1 LAST SIZE 1B
J 0
(-1950 3700);
DISPLAY 1.170213 (-1950 3700);
PAINT AQUA (-1950 3700);
DISPLAY INVISIBLE (-1950 3700);
FORCEPROP 1 LAST PATH I66
J 0
(-1950 3750);
DISPLAY 0.872340 (-1950 3750);
PAINT AQUA (-1950 3750);
DISPLAY INVISIBLE (-1950 3750);
FORCEPROP 2 LAST CDS_LIB mstr_symbols
J 0
(-2025 3750);
PAINT MONO (-2025 3750);
DISPLAY INVISIBLE (-2025 3750);
FORCEPROP 1 LAST BODY_TYPE PLUMBING
J 0
(-2070 3707);
DISPLAY 0.340426 (-2070 3707);
PAINT GREEN (-2070 3707);
DISPLAY INVISIBLE (-2070 3707);
FORCEPROP 1 LAST HDL_POWER GND
J 0
(-2025 3900);
DISPLAY 1.170213 (-2025 3900);
PAINT GREEN (-2025 3900);
DISPLAY INVISIBLE (-2025 3900);
FORCEADD GND..1
(-2050 2925);
FORCEPROP 3 LASTPIN (-2050 2975) SIG_NAME GND\g
J 0
(-2040 2985);
DISPLAY 0.659574 (-2040 2985);
PAINT MONO (-2040 2985);
DISPLAY INVISIBLE (-2040 2985);
FORCEPROP 2 LAST ROOM PVCCIN_CPU0_PWR_VR
J 0
(-2600 3000);
DISPLAY 1.936170 (-2600 3000);
PAINT ORANGE (-2600 3000);
DISPLAY INVISIBLE (-2600 3000);
FORCEPROP 2 LAST BOM_COST PROC_VRD_VCCIN_CPU0
J 0
(-2425 3000);
DISPLAY 1.446809 (-2425 3000);
PAINT MONO (-2425 3000);
DISPLAY INVISIBLE (-2425 3000);
FORCEPROP 1 LAST VOLTAGE 0
J 0
(-2050 2925);
PAINT SKYBLUE (-2050 2925);
DISPLAY INVISIBLE (-2050 2925);
FORCEPROP 1 LAST SIZE 1B
J 0
(-1975 2875);
DISPLAY 1.723404 (-1975 2875);
PAINT GREEN (-1975 2875);
DISPLAY INVISIBLE (-1975 2875);
FORCEPROP 1 LAST PATH I67
J 0
(-1975 2925);
DISPLAY 0.872340 (-1975 2925);
PAINT AQUA (-1975 2925);
DISPLAY INVISIBLE (-1975 2925);
FORCEPROP 2 LAST CDS_LIB mstr_symbols
J 0
(-2050 2925);
PAINT MONO (-2050 2925);
DISPLAY INVISIBLE (-2050 2925);
FORCEPROP 1 LAST BODY_TYPE PLUMBING
J 0
(-2095 2882);
DISPLAY 0.340426 (-2095 2882);
PAINT GREEN (-2095 2882);
DISPLAY INVISIBLE (-2095 2882);
FORCEPROP 1 LAST HDL_POWER GND
J 0
(-2050 3075);
DISPLAY 1.723404 (-2050 3075);
PAINT GREEN (-2050 3075);
DISPLAY INVISIBLE (-2050 3075);
FORCEADD CAP_A..1
(-3850 3425);
FORCEPROP 1 LASTPIN (-3850 3325) $PN 2
J 0
(-3840 3305);
DISPLAY 0.787234 (-3840 3305);
PAINT ORANGE (-3840 3305);
FORCEPROP 1 LASTPIN (-3850 3525) $PN 1
J 0
(-3840 3505);
DISPLAY 0.787234 (-3840 3505);
PAINT ORANGE (-3840 3505);
FORCEPROP 1 LAST VALUE 0.1UF
J 0
(-3800 3475);
DISPLAY 0.617021 (-3800 3475);
PAINT SKYBLUE (-3800 3475);
FORCEPROP 1 LAST TOLERANCE 10%
J 0
(-3800 3375);
DISPLAY 0.617021 (-3800 3375);
PAINT SKYBLUE (-3800 3375);
FORCEPROP 1 LAST MATERIAL X7R
J 0
(-3800 3325);
DISPLAY 0.617021 (-3800 3325);
PAINT SKYBLUE (-3800 3325);
FORCEPROP 1 LAST PART_NUMBER A36096-030
J 0
(-3800 3275);
DISPLAY 0.617021 (-3800 3275);
PAINT BLUE (-3800 3275);
FORCEPROP 1 LAST PACK_TYPE 0402V
J 0
(-3800 3225);
DISPLAY 0.617021 (-3800 3225);
PAINT SKYBLUE (-3800 3225);
FORCEPROP 1 LAST LOCATION CT60
J 0
(-4000 3425);
DISPLAY 0.617021 (-4000 3425);
PAINT AQUA (-4000 3425);
FORCEPROP 1 LAST VOLTAGE 16V
J 0
(-3800 3425);
DISPLAY 0.617021 (-3800 3425);
PAINT SKYBLUE (-3800 3425);
FORCEPROP 0 LAST POP NOPOP
J 0
(-4125 3350);
DISPLAY 1.021277 (-4125 3350);
PAINT RED (-4125 3350);
FORCEPROP 2 LAST ROOM PVCCIN_CPU0_PWR_VR
J 0
(-3800 3575);
DISPLAY 1.361702 (-3800 3575);
PAINT ORANGE (-3800 3575);
DISPLAY INVISIBLE (-3800 3575);
FORCEPROP 1 LAST PATH I69
J 0
(-3800 3575);
DISPLAY 0.978723 (-3800 3575);
PAINT WHITE (-3800 3575);
DISPLAY INVISIBLE (-3800 3575);
FORCEPROP 2 LAST CDS_LIB dev_discrete
J 0
(-3850 3425);
PAINT MONO (-3850 3425);
DISPLAY INVISIBLE (-3850 3425);
FORCEPROP 0 LAST SEC 1
J 0
(-3800 3525);
DISPLAY 0.680851 (-3800 3525);
PAINT MONO (-3800 3525);
DISPLAY INVISIBLE (-3800 3525);
FORCEPROP 2 LAST SEC_TYPE 0402V
J 0
(-3800 3625);
DISPLAY 1.021277 (-3800 3625);
PAINT ORANGE (-3800 3625);
DISPLAY INVISIBLE (-3800 3625);
FORCEADD GND..1
(-3850 3175);
FORCEPROP 3 LASTPIN (-3850 3225) SIG_NAME GND\g
J 0
(-3840 3235);
DISPLAY 0.659574 (-3840 3235);
PAINT MONO (-3840 3235);
DISPLAY INVISIBLE (-3840 3235);
FORCEPROP 2 LAST CDS_LIB mstr_symbols
J 0
(-3850 3175);
PAINT MONO (-3850 3175);
DISPLAY INVISIBLE (-3850 3175);
FORCEPROP 1 LAST PATH I70
J 0
(-3775 3175);
DISPLAY 0.872340 (-3775 3175);
PAINT AQUA (-3775 3175);
DISPLAY INVISIBLE (-3775 3175);
FORCEPROP 1 LAST VOLTAGE 0
J 0
(-3850 3175);
PAINT SKYBLUE (-3850 3175);
DISPLAY INVISIBLE (-3850 3175);
FORCEPROP 1 LAST SIZE 1B
J 0
(-3775 3125);
DISPLAY 1.723404 (-3775 3125);
PAINT GREEN (-3775 3125);
DISPLAY INVISIBLE (-3775 3125);
FORCEPROP 2 LAST BOM_COST PROC_VRD_VCCIN_CPU0
J 0
(-4225 3250);
DISPLAY 1.446809 (-4225 3250);
PAINT MONO (-4225 3250);
DISPLAY INVISIBLE (-4225 3250);
FORCEPROP 2 LAST ROOM PVCCIN_CPU0_PWR_VR
J 0
(-4400 3250);
DISPLAY 1.936170 (-4400 3250);
PAINT ORANGE (-4400 3250);
DISPLAY INVISIBLE (-4400 3250);
FORCEPROP 1 LAST BODY_TYPE PLUMBING
J 0
(-3895 3132);
DISPLAY 0.340426 (-3895 3132);
PAINT GREEN (-3895 3132);
DISPLAY INVISIBLE (-3895 3132);
FORCEPROP 1 LAST HDL_POWER GND
J 0
(-3850 3325);
DISPLAY 1.723404 (-3850 3325);
PAINT GREEN (-3850 3325);
DISPLAY INVISIBLE (-3850 3325);
FORCEADD CAP..1
(-2050 3475);
FORCEPROP 1 LASTPIN (-2050 3575) $PN 1
J 0
(-2040 3555);
DISPLAY 0.787234 (-2040 3555);
PAINT ORANGE (-2040 3555);
FORCEPROP 1 LAST VOLTAGE 50V
J 0
(-2000 3475);
DISPLAY 0.617021 (-2000 3475);
PAINT SKYBLUE (-2000 3475);
FORCEPROP 1 LASTPIN (-2050 3375) $PN 2
J 0
(-2040 3355);
DISPLAY 0.787234 (-2040 3355);
PAINT ORANGE (-2040 3355);
FORCEPROP 1 LAST MATERIAL X7R
J 0
(-2000 3375);
DISPLAY 0.617021 (-2000 3375);
PAINT SKYBLUE (-2000 3375);
FORCEPROP 1 LAST TOLERANCE 10%
J 0
(-2000 3425);
DISPLAY 0.617021 (-2000 3425);
PAINT SKYBLUE (-2000 3425);
FORCEPROP 0 LAST POP NOPOP
J 0
(-1850 3475);
DISPLAY 0.808511 (-1850 3475);
PAINT RED (-1850 3475);
FORCEPROP 1 LAST LOCATION CT59
J 0
(-2000 3575);
DISPLAY 0.617021 (-2000 3575);
PAINT AQUA (-2000 3575);
FORCEPROP 1 LAST VALUE 1000PF
J 0
(-2000 3525);
DISPLAY 0.617021 (-2000 3525);
PAINT SKYBLUE (-2000 3525);
FORCEPROP 1 LAST PACK_TYPE 0402LF
J 0
(-1850 3525);
DISPLAY 0.617021 (-1850 3525);
PAINT SKYBLUE (-1850 3525);
FORCEPROP 1 LAST PART_NUMBER A36096-046
J 0
(-1875 3575);
DISPLAY 0.617021 (-1875 3575);
PAINT BLUE (-1875 3575);
FORCEPROP 2 LAST CDS_LIB mstr_discrete
J 0
(-2050 3475);
PAINT MONO (-2050 3475);
DISPLAY INVISIBLE (-2050 3475);
FORCEPROP 1 LAST PATH I76
J 0
(-2000 3625);
DISPLAY 0.978723 (-2000 3625);
PAINT WHITE (-2000 3625);
DISPLAY INVISIBLE (-2000 3625);
FORCEPROP 0 LAST ROOM VDDQ_KLM_PWR_VR
J 0
(-2000 3675);
DISPLAY 1.021277 (-2000 3675);
PAINT ORANGE (-2000 3675);
DISPLAY INVISIBLE (-2000 3675);
FORCEPROP 0 LAST SEC 1
J 0
(-2000 3625);
DISPLAY 0.680851 (-2000 3625);
PAINT MONO (-2000 3625);
DISPLAY INVISIBLE (-2000 3625);
FORCEPROP 2 LAST SEC_TYPE 0402LF
J 0
(-2000 3675);
DISPLAY 1.021277 (-2000 3675);
PAINT ORANGE (-2000 3675);
DISPLAY INVISIBLE (-2000 3675);
FORCEADD RES..1
(-5250 3700);
FORCEPROP 1 LASTPIN (-5150 3700) $PN 2
J 0
(-5188 3712);
DISPLAY 0.787234 (-5188 3712);
PAINT ORANGE (-5188 3712);
FORCEPROP 1 LASTPIN (-5350 3700) $PN 1
J 0
(-5338 3712);
DISPLAY 0.787234 (-5338 3712);
PAINT ORANGE (-5338 3712);
FORCEPROP 1 LAST PACK_TYPE 0603
J 0
(-5175 3650);
DISPLAY 0.617021 (-5175 3650);
PAINT SKYBLUE (-5175 3650);
FORCEPROP 1 LAST VALUE 0
J 2
(-5300 3650);
DISPLAY 0.617021 (-5300 3650);
PAINT SKYBLUE (-5300 3650);
FORCEPROP 1 LAST PART_NUMBER G22178-002
J 0
(-5350 3600);
DISPLAY 0.617021 (-5350 3600);
PAINT BLUE (-5350 3600);
FORCEPROP 1 LAST TOLERANCE 5.0%
J 0
(-5050 3600);
DISPLAY 0.617021 (-5050 3600);
PAINT SKYBLUE (-5050 3600);
FORCEPROP 1 LAST WATTAGE 1/10W
J 0
(-5125 3550);
DISPLAY 0.617021 (-5125 3550);
PAINT SKYBLUE (-5125 3550);
FORCEPROP 1 LAST MATERIAL CHIP
J 0
(-5250 3550);
DISPLAY 0.617021 (-5250 3550);
PAINT SKYBLUE (-5250 3550);
FORCEPROP 1 LAST LOCATION RT40
J 0
(-5375 3550);
DISPLAY 0.617021 (-5375 3550);
PAINT AQUA (-5375 3550);
FORCEPROP 0 LAST BOM_COST NT_GBE_BASE
J 0
(-5150 3925);
DISPLAY 1.021277 (-5150 3925);
PAINT ORANGE (-5150 3925);
DISPLAY INVISIBLE (-5150 3925);
FORCEPROP 0 LAST ROOM NIC_SPRV
J 0
(-5150 3825);
DISPLAY 1.021277 (-5150 3825);
PAINT ORANGE (-5150 3825);
DISPLAY INVISIBLE (-5150 3825);
FORCEPROP 1 LAST PATH I78
J 0
(-5300 3850);
DISPLAY 0.978723 (-5300 3850);
PAINT WHITE (-5300 3850);
DISPLAY INVISIBLE (-5300 3850);
FORCEPROP 2 LAST CDS_LIB mstr_discrete
J 0
(-5250 3700);
PAINT MONO (-5250 3700);
DISPLAY INVISIBLE (-5250 3700);
FORCEPROP 0 LAST SEC 1
J 0
(-5500 3800);
DISPLAY 0.680851 (-5500 3800);
PAINT MONO (-5500 3800);
DISPLAY INVISIBLE (-5500 3800);
FORCEPROP 2 LAST SEC_TYPE 0603
J 0
(-5300 3900);
DISPLAY 1.021277 (-5300 3900);
PAINT ORANGE (-5300 3900);
DISPLAY INVISIBLE (-5300 3900);
FORCEADD RES..1
(-5850 4725);
FORCEPROP 1 LAST MATERIAL CHIP
J 0
(-5800 4550);
DISPLAY 0.638298 (-5800 4550);
PAINT SKYBLUE (-5800 4550);
FORCEPROP 1 LAST WATTAGE 1/16W
J 0
(-5975 4550);
DISPLAY 0.638298 (-5975 4550);
PAINT SKYBLUE (-5975 4550);
FORCEPROP 1 LAST PACK_TYPE 0402
J 0
(-5775 4625);
DISPLAY 0.617021 (-5775 4625);
PAINT SKYBLUE (-5775 4625);
FORCEPROP 1 LAST TOLERANCE 5%
J 0
(-5900 4625);
DISPLAY 0.617021 (-5900 4625);
PAINT SKYBLUE (-5900 4625);
FORCEPROP 1 LAST VALUE 0.0
J 2
(-5950 4625);
DISPLAY 0.617021 (-5950 4625);
PAINT SKYBLUE (-5950 4625);
FORCEPROP 1 LASTPIN (-5950 4725) $PN 1
J 0
(-5938 4737);
DISPLAY 0.617021 (-5938 4737);
PAINT WHITE (-5938 4737);
FORCEPROP 1 LAST PART_NUMBER G21497-005
J 0
(-5975 4675);
DISPLAY 0.617021 (-5975 4675);
PAINT BLUE (-5975 4675);
FORCEPROP 1 LAST LOCATION R6N3
J 0
(-5950 4775);
DISPLAY 0.617021 (-5950 4775);
PAINT AQUA (-5950 4775);
FORCEPROP 1 LASTPIN (-5750 4725) $PN 2
J 0
(-5788 4737);
DISPLAY 0.617021 (-5788 4737);
PAINT WHITE (-5788 4737);
FORCEPROP 2 LAST CDS_LOCATION R6N3
J 0
(-6325 4725);
DISPLAY 0.617021 (-6325 4725);
PAINT AQUA (-6325 4725);
DISPLAY INVISIBLE (-6325 4725);
FORCEPROP 0 LAST CDS_SEC 1
J 0
(-5550 4775);
PAINT MONO (-5550 4775);
DISPLAY INVISIBLE (-5550 4775);
FORCEPROP 2 LAST ROOM CPU0
J 0
(-5900 4875);
PAINT PEACH (-5900 4875);
DISPLAY INVISIBLE (-5900 4875);
FORCEPROP 2 LAST SEC 1
J 0
(-5900 4950);
DISPLAY 0.680851 (-5900 4950);
PAINT MONO (-5900 4950);
DISPLAY INVISIBLE (-5900 4950);
FORCEPROP 2 LAST SEC_TYPE 0402
J 0
(-5900 4950);
DISPLAY 1.021277 (-5900 4950);
PAINT ORANGE (-5900 4950);
DISPLAY INVISIBLE (-5900 4950);
FORCEPROP 2 LAST CDS_LIB mstr_discrete
J 0
(-5850 4725);
DISPLAY 1.340426 (-5850 4725);
PAINT ORANGE (-5850 4725);
DISPLAY INVISIBLE (-5850 4725);
FORCEPROP 2 LAST BOM_COST PROC_SIDEBAND
J 0
(-5850 4725);
PAINT MONO (-5850 4725);
DISPLAY INVISIBLE (-5850 4725);
FORCEPROP 1 LAST PATH I81
J 0
(-5900 4875);
DISPLAY 0.978723 (-5900 4875);
PAINT WHITE (-5900 4875);
DISPLAY INVISIBLE (-5900 4875);
FORCEADD IND-300NH-20-GP..1
R 1
(-1325 3650);
FORCEPROP 2 LAST TYPE IRMS=66A@DELTA_T<40C
J 0
(-1500 3425);
DISPLAY 0.638298 (-1500 3425);
PAINT GREEN (-1500 3425);
FORCEPROP 2 LAST PACK_SIZE DCR=0.17MOHM
J 0
(-1500 3375);
DISPLAY 0.638298 (-1500 3375);
PAINT GREEN (-1500 3375);
FORCEPROP 2 LAST RATED ISAT=33A@25C
J 0
(-1500 3475);
DISPLAY 0.638298 (-1500 3475);
PAINT GREEN (-1500 3475);
FORCEPROP 2 LAST ATTRIBUTE 300NH
J 0
(-1500 3525);
DISPLAY 0.638298 (-1500 3525);
PAINT GREEN (-1500 3525);
FORCEPROP 2 LASTPIN (-1475 3625) $PN 1
J 2
(-1485 3635);
DISPLAY 0.808511 (-1485 3635);
PAINT ORANGE (-1485 3635);
FORCEPROP 1 LAST LOCATION L4C2
J 0
(-1475 3700);
DISPLAY 0.617021 (-1475 3700);
PAINT GREEN (-1475 3700);
FORCEPROP 2 LASTPIN (-1175 3625) $PN 2
J 0
(-1165 3635);
DISPLAY 0.808511 (-1165 3635);
PAINT ORANGE (-1165 3635);
FORCEPROP 1 LAST VALUE IND-300NH-20-GP
J 0
(-1500 3575);
DISPLAY 0.617021 (-1500 3575);
PAINT GREEN (-1500 3575);
FORCEPROP 1 LAST PATH I82
R 1
J 0
(-1325 3650);
DISPLAY 0.617021 (-1325 3650);
PAINT GREEN (-1325 3650);
DISPLAY INVISIBLE (-1325 3650);
FORCEPROP 1 LAST PART_NUMBER 068.3012N.M001
R 1
J 0
(-1325 3650);
DISPLAY 0.617021 (-1325 3650);
PAINT GREEN (-1325 3650);
DISPLAY INVISIBLE (-1325 3650);
FORCEPROP 2 LAST CDS_LIB w_hdl
R 1
J 0
(-1325 3650);
PAINT MONO (-1325 3650);
DISPLAY INVISIBLE (-1325 3650);
FORCEPROP 1 LAST CDS_LMAN_SYM_OUTLINE -75,100,75,-100
R 1
J 0
(-1325 3650);
DISPLAY 0.468085 (-1325 3650);
PAINT GREEN (-1325 3650);
DISPLAY INVISIBLE (-1325 3650);
FORCEPROP 2 LAST SEC_TYPE DISCRET-GB1
J 0
(-1475 3750);
DISPLAY 1.021277 (-1475 3750);
PAINT ORANGE (-1475 3750);
DISPLAY INVISIBLE (-1475 3750);
FORCEPROP 2 LAST SEC 1
J 0
(-1475 3750);
DISPLAY 0.680851 (-1475 3750);
PAINT MONO (-1475 3750);
DISPLAY INVISIBLE (-1475 3750);
FORCEPROP 1 LAST PACK_TYPE DISCRET-GB1
R 1
J 0
(-1325 3650);
DISPLAY 0.617021 (-1325 3650);
PAINT GREEN (-1325 3650);
DISPLAY INVISIBLE (-1325 3650);
FORCEADD SC1U10V2KX-4-GP..1
(-5625 4175);
FORCEPROP 2 LAST PACK_SIZE 0402
J 0
(-5500 4050);
DISPLAY 0.638298 (-5500 4050);
PAINT GREEN (-5500 4050);
FORCEPROP 2 LAST RATED 10V
J 0
(-5500 4100);
DISPLAY 0.638298 (-5500 4100);
PAINT GREEN (-5500 4100);
FORCEPROP 2 LAST TOLERANCE 10%
J 0
(-5500 4150);
DISPLAY 0.638298 (-5500 4150);
PAINT GREEN (-5500 4150);
FORCEPROP 2 LAST ATTRIBUTE 1UF
J 0
(-5500 4200);
DISPLAY 0.638298 (-5500 4200);
PAINT GREEN (-5500 4200);
FORCEPROP 1 LAST VALUE SC1U10V2KX-4-GP
R 1
J 0
(-5525 3950);
DISPLAY 0.617021 (-5525 3950);
PAINT GREEN (-5525 3950);
FORCEPROP 2 LASTPIN (-5625 4100) $PN 2
R 1
J 2
(-5635 4090);
DISPLAY 0.808511 (-5635 4090);
PAINT ORANGE (-5635 4090);
FORCEPROP 2 LASTPIN (-5625 4250) $PN 1
R 1
J 0
(-5635 4260);
DISPLAY 0.808511 (-5635 4260);
PAINT ORANGE (-5635 4260);
FORCEPROP 1 LAST LOCATION C4C4
J 0
(-5500 4255);
DISPLAY 0.617021 (-5500 4255);
PAINT GREEN (-5500 4255);
FORCEPROP 1 LAST CDS_LMAN_SYM_OUTLINE -50,25,50,-25
J 0
(-5625 4175);
DISPLAY 0.468085 (-5625 4175);
PAINT GREEN (-5625 4175);
DISPLAY INVISIBLE (-5625 4175);
FORCEPROP 1 LAST PATH I83
J 0
(-5625 4175);
DISPLAY 0.617021 (-5625 4175);
PAINT GREEN (-5625 4175);
DISPLAY INVISIBLE (-5625 4175);
FORCEPROP 2 LAST CDS_LIB w_hdl
J 0
(-5625 4175);
PAINT MONO (-5625 4175);
DISPLAY INVISIBLE (-5625 4175);
FORCEPROP 1 LAST PART_NUMBER 78.10523.8FL
J 0
(-5625 4175);
DISPLAY 0.617021 (-5625 4175);
PAINT GREEN (-5625 4175);
DISPLAY INVISIBLE (-5625 4175);
FORCEPROP 2 LAST SEC_TYPE SMD-BCG6
J 0
(-5600 4250);
DISPLAY 1.021277 (-5600 4250);
PAINT ORANGE (-5600 4250);
DISPLAY INVISIBLE (-5600 4250);
FORCEPROP 2 LAST SEC 1
J 0
(-5600 4250);
DISPLAY 0.680851 (-5600 4250);
PAINT MONO (-5600 4250);
DISPLAY INVISIBLE (-5600 4250);
FORCEPROP 1 LAST PACK_TYPE SMD-BCG6
J 0
(-5625 4175);
DISPLAY 0.617021 (-5625 4175);
PAINT GREEN (-5625 4175);
DISPLAY INVISIBLE (-5625 4175);
FORCEADD 1R3F-GP..1
(-2050 3150);
FORCEPROP 1 LAST LOCATION RT39
J 0
(-2000 3250);
DISPLAY 0.617021 (-2000 3250);
PAINT GREEN (-2000 3250);
FORCEPROP 0 LAST POP NOPOP
J 0
(-2000 2950);
DISPLAY 0.638298 (-2000 2950);
PAINT RED (-2000 2950);
FORCEPROP 1 LAST VALUE 1R3F-GP
J 0
(-2000 3200);
DISPLAY 0.617021 (-2000 3200);
PAINT GREEN (-2000 3200);
FORCEPROP 2 LAST TOLERANCE 1%
J 0
(-2000 3100);
DISPLAY 0.638298 (-2000 3100);
PAINT GREEN (-2000 3100);
FORCEPROP 2 LAST RATED 1/10W
J 0
(-2000 3050);
DISPLAY 0.638298 (-2000 3050);
PAINT GREEN (-2000 3050);
FORCEPROP 2 LASTPIN (-2050 3275) $PN 1
R 1
J 0
(-2060 3285);
DISPLAY 0.808511 (-2060 3285);
PAINT ORANGE (-2060 3285);
FORCEPROP 2 LASTPIN (-2050 3025) $PN 2
R 1
J 2
(-2060 3015);
DISPLAY 0.808511 (-2060 3015);
PAINT ORANGE (-2060 3015);
FORCEPROP 2 LAST ATTRIBUTE 1 OHM
J 0
(-2000 3150);
DISPLAY 0.638298 (-2000 3150);
PAINT GREEN (-2000 3150);
FORCEPROP 2 LAST PACK_SIZE 0603
J 0
(-2000 3000);
DISPLAY 0.638298 (-2000 3000);
PAINT GREEN (-2000 3000);
FORCEPROP 1 LAST PATH I84
J 0
(-2050 3150);
DISPLAY 0.617021 (-2050 3150);
PAINT GREEN (-2050 3150);
DISPLAY INVISIBLE (-2050 3150);
FORCEPROP 1 LAST CDS_LMAN_SYM_OUTLINE -50,75,50,-75
J 0
(-2050 3150);
DISPLAY 0.468085 (-2050 3150);
PAINT GREEN (-2050 3150);
DISPLAY INVISIBLE (-2050 3150);
FORCEPROP 2 LAST CDS_LIB w_hdl
J 0
(-2050 3150);
DISPLAY INVISIBLE (-2050 3150);
FORCEPROP 1 LAST PART_NUMBER 64.1R005.55L
J 0
(-2050 3150);
DISPLAY 0.617021 (-2050 3150);
PAINT GREEN (-2050 3150);
DISPLAY INVISIBLE (-2050 3150);
FORCEPROP 2 LAST SEC_TYPE RCL_GP
J 0
(-2000 3250);
DISPLAY 1.021277 (-2000 3250);
PAINT ORANGE (-2000 3250);
DISPLAY INVISIBLE (-2000 3250);
FORCEPROP 2 LAST SEC 1
J 0
(-2000 3250);
DISPLAY 0.680851 (-2000 3250);
PAINT MONO (-2000 3250);
DISPLAY INVISIBLE (-2000 3250);
FORCEPROP 1 LAST PACK_TYPE RCL_GP
J 0
(-2050 3150);
DISPLAY 0.617021 (-2050 3150);
PAINT GREEN (-2050 3150);
DISPLAY INVISIBLE (-2050 3150);
FORCEADD DNS..2
(-770 4095);
PAINT RED (-770 4095);
FORCEPROP 2 LAST CDS_LIB mstr_misc
J 0
(-770 4095);
PAINT ORANGE (-770 4095);
DISPLAY INVISIBLE (-770 4095);
FORCEPROP 1 LAST COMMENT_BODY TRUE
R 1
J 0
(-695 3870);
DISPLAY 0.872340 (-695 3870);
PAINT GREEN (-695 3870);
DISPLAY INVISIBLE (-695 3870);
FORCEADD DESIGN_NOTE..1
(-975 1525);
PAINT PURPLE (-975 1525);
FORCEPROP 2 LAST CDS_LIB mstr_symbols
J 0
(-975 1525);
PAINT ORANGE (-975 1525);
DISPLAY INVISIBLE (-975 1525);
FORCEPROP 2 LAST BOM_COST SM_CONTROLLER
J 0
(-1175 1475);
PAINT MONO (-1175 1475);
DISPLAY INVISIBLE (-1175 1475);
FORCEPROP 2 LAST ROOM PVCCIN_CPU0_VR
J 0
(-1175 1475);
PAINT MONO (-1175 1475);
DISPLAY INVISIBLE (-1175 1475);
FORCEPROP 1 LAST COMMENT_BODY TRUE
J 0
(-950 1625);
DISPLAY 1.319149 (-950 1625);
PAINT GREEN (-950 1625);
DISPLAY INVISIBLE (-950 1625);
FORCEADD INTEL_CORP_BPAGE..1
(0 0);
FORCEPROP 1 LAST CDS_CON_LAST_MODIFIED Fri Jun 16 17:49:14 2017
J 0
(-1425 325);
PAINT ORANGE (-1425 325);
DISPLAY INVISIBLE (-1425 325);
FORCEPROP 1 LAST CUSTOM_TXT_CDS <CURRENT_DESIGN_SHEET> OF <TOTAL_DESIGN_SHEETS>
J 0
(-500 25);
PAINT ORANGE (-500 25);
FORCEPROP 1 LAST CUSTOM_TXT_CDS <CON_LAST_MODIFIED>
J 0
(-4000 100);
PAINT ORANGE (-4000 100);
FORCEPROP 2 LAST CUSTOM_TXT_CDS <XR_PAGE_TITLE>
J 0
(-7890 5250);
DISPLAY 0.638298 (-7890 5250);
PAINT PINK (-7890 5250);
DISPLAY INVISIBLE (-7890 5250);
FORCEPROP 1 LAST SCH_TITLE VSA CPU0
J 0
(-7950 50);
DISPLAY 1.212766 (-7950 50);
PAINT ORANGE (-7950 50);
FORCEPROP 2 LAST CDS_LIB mstr_symbols
J 0
(0 0);
PAINT MONO (0 0);
DISPLAY INVISIBLE (0 0);
FORCEPROP 2 LAST PAGE_BORDER TRUE
J 0
(-7890 5250);
DISPLAY 0.638298 (-7890 5250);
PAINT PINK (-7890 5250);
DISPLAY INVISIBLE (-7890 5250);
FORCEPROP 1 LAST COMMENT_BODY TRUE
J 0
(12 12);
DISPLAY 0.468085 (12 12);
PAINT GREEN (12 12);
DISPLAY INVISIBLE (12 12);
FORCEPROP 2 LAST CDS_XR_PAGE_TITLE CR-205 : @BASEBOARD_FAB2_LIB.BASEBOARD_FAB2(SCH_1):PAGE205
J 0
(-7890 5250);
DISPLAY 0.638298 (-7890 5250);
PAINT PINK (-7890 5250);
DISPLAY INVISIBLE (-7890 5250);
FORCEADD DNS..2
(-5745 1820);
PAINT RED (-5745 1820);
FORCEPROP 2 LAST CDS_LIB mstr_misc
J 0
(-5745 1820);
PAINT ORANGE (-5745 1820);
DISPLAY INVISIBLE (-5745 1820);
FORCEPROP 1 LAST COMMENT_BODY TRUE
R 1
J 0
(-5670 1595);
DISPLAY 0.872340 (-5670 1595);
PAINT GREEN (-5670 1595);
DISPLAY INVISIBLE (-5670 1595);
FORCEADD DESIGN_NOTE..1
(-1025 1750);
PAINT PURPLE (-1025 1750);
FORCEPROP 0 LAST L1 PVCCSA CPU SPECIFICATIONS:
J 0
(-1220 1625);
PAINT VIOLET (-1220 1625);
FORCEPROP 2 LAST CDS_LIB mstr_symbols
J 0
(-1025 1750);
PAINT ORANGE (-1025 1750);
DISPLAY INVISIBLE (-1025 1750);
FORCEPROP 2 LAST BOM_COST SM_CONTROLLER
J 0
(-1225 1700);
PAINT MONO (-1225 1700);
DISPLAY INVISIBLE (-1225 1700);
FORCEPROP 2 LAST ROOM PVCCIN_CPU0_VR
J 0
(-1225 1700);
PAINT MONO (-1225 1700);
DISPLAY INVISIBLE (-1225 1700);
FORCEPROP 1 LAST COMMENT_BODY TRUE
J 0
(-1000 1850);
DISPLAY 1.319149 (-1000 1850);
PAINT GREEN (-1000 1850);
DISPLAY INVISIBLE (-1000 1850);
WIRE 16 -1 (-2000 1500)(-2000 1550);
WIRE 16 -1 (-2650 1500)(-2000 1500);
WIRE 16 -1 (-2000 1450)(-2000 1500);
WIRE 16 -1 (-2650 1450)(-2650 1500);
WIRE 16 -1 (-2000 1025)(-2000 1050);
WIRE 16 -1 (-2650 1050)(-2000 1050);
WIRE 16 -1 (-2000 1050)(-2000 1250);
WIRE 16 -1 (-2650 1250)(-2650 1050);
WIRE 16 -1 (-2475 3325)(-2475 3375);
WIRE 16 -1 (-2475 3375)(-2475 3425);
WIRE 16 -1 (-2475 3375)(-2650 3375);
WIRE 16 -1 (-2475 3425)(-2475 3475);
WIRE 16 -1 (-2475 3425)(-2650 3425);
WIRE 16 -1 (-2475 3475)(-2475 3525);
WIRE 16 -1 (-2475 3475)(-2650 3475);
WIRE 16 -1 (-2650 3525)(-2475 3525);
WIRE 16 -1 (-4300 2425)(-4300 2600);
WIRE 16 -1 (-5000 2425)(-4300 2425);
WIRE 16 -1 (-4250 1100)(-4250 1200);
WIRE 16 -1 (-4250 1200)(-4975 1200);
WIRE 16 -1 (-7175 4625)(-7175 4375);
WIRE 16 -1 (-7175 4375)(-6925 4375);
WIRE 16 -1 (-7175 4300)(-7175 4375);
WIRE 16 -1 (-6925 4375)(-6700 4375);
WIRE 16 -1 (-6925 4300)(-6925 4375);
WIRE 16 -1 (-6700 4375)(-6475 4375);
WIRE 16 -1 (-6700 4300)(-6700 4375);
WIRE 16 -1 (-6250 4375)(-6475 4375);
WIRE 16 -1 (-6475 4300)(-6475 4375);
WIRE 16 -1 (-6250 4375)(-3775 4375);
WIRE 16 -1 (-6250 4300)(-6250 4375);
WIRE 16 -1 (-3775 4425)(-3775 4375);
WIRE 16 -1 (-3775 4375)(-3650 4375);
WIRE 16 -1 (-3775 4425)(-3650 4425);
WIRE 16 -1 (-6925 3775)(-6925 3950);
WIRE 16 -1 (-6925 3950)(-6700 3950);
WIRE 16 -1 (-7175 3950)(-6925 3950);
WIRE 16 -1 (-6925 4100)(-6925 3950);
WIRE 16 -1 (-7175 4100)(-7175 3950);
WIRE 16 -1 (-6700 3950)(-6475 3950);
WIRE 16 -1 (-6700 4100)(-6700 3950);
WIRE 16 -1 (-6250 3950)(-6475 3950);
WIRE 16 -1 (-6475 4100)(-6475 3950);
WIRE 16 -1 (-6000 3950)(-6250 3950);
WIRE 16 -1 (-6250 4100)(-6250 3950);
WIRE 16 -1 (-6000 3950)(-5625 3950);
WIRE 16 -1 (-6000 4100)(-6000 3950);
WIRE 16 -1 (-5300 3950)(-5625 3950);
WIRE 16 -1 (-5625 4100)(-5625 3950);
WIRE 16 -1 (-5300 4100)(-5300 3950);
WIRE 16 -1 (-275 3625)(-275 3675);
WIRE 16 -1 (-275 3625)(-600 3625);
WIRE 16 -1 (-275 3175)(-275 3625);
WIRE 16 -1 (-600 3625)(-950 3625);
WIRE 16 -1 (-600 3175)(-600 3625);
WIRE 16 -1 (-950 3625)(-1050 3625);
WIRE 16 -1 (-950 3175)(-950 3625);
WIRE 16 -1 (-1050 2900)(-1050 3625);
WIRE 16 -1 (-1175 3625)(-1050 3625);
WIRE 16 -1 (-3800 2900)(-1050 2900);
WIRE 16 -1 (-3800 4075)(-3800 2900);
WIRE 16 -1 (-3650 4075)(-3800 4075);
WIRE 16 -1 (-4550 4800)(-4550 4725);
WIRE 16 -1 (-4550 4725)(-4550 4275);
WIRE 16 -1 (-4550 4725)(-5300 4725);
WIRE 16 -1 (-5300 4725)(-5625 4725);
WIRE 16 -1 (-5300 4300)(-5300 4725);
WIRE 16 -1 (-4550 4275)(-3750 4275);
WIRE 16 -1 (-3750 4175)(-3750 4275);
WIRE 16 -1 (-3750 4275)(-3650 4275);
WIRE 16 -1 (-5625 4250)(-5625 4725);
WIRE 16 -1 (-5625 4725)(-5750 4725);
WIRE 16 -1 (-3650 4175)(-3750 4175);
WIRE 16 -1 (-275 2775)(-275 2825);
WIRE 16 -1 (-275 2825)(-600 2825);
WIRE 16 -1 (-275 2975)(-275 2825);
WIRE 16 -1 (-600 2825)(-950 2825);
WIRE 16 -1 (-600 2975)(-600 2825);
WIRE 16 -1 (-950 2825)(-950 2975);
WIRE 16 -1 (-775 4000)(-775 3875);
WIRE 16 -1 (-2025 3850)(-2025 3800);
WIRE 16 -1 (-2050 3025)(-2050 2975);
WIRE 16 -1 (-3850 3325)(-3850 3225);
WIRE 16 -1 (-7150 2075)(-6300 2075);
FORCEPROP 2 LAST SIG_NAME VSENSE_PVSA_CPU0_P
J 0
(-7120 2095);
DISPLAY 0.617021 (-7120 2095);
PAINT ORANGE (-7120 2095);
WIRE 16 -1 (-6300 1875)(-6300 2075);
WIRE 16 -1 (-6300 1875)(-5975 1875);
WIRE 16 -1 (-5975 1875)(-5975 2025);
WIRE 16 -1 (-5975 2025)(-5750 2025);
WIRE 16 -1 (-5750 1925)(-5750 2025);
WIRE 16 -1 (-5350 2025)(-5750 2025);
WIRE 16 -1 (-5175 2025)(-5350 2025);
WIRE 16 -1 (-5350 2425)(-5350 2025);
WIRE 16 -1 (-5200 2425)(-5350 2425);
WIRE 3 2175 (-4275 3150)(-3550 3150);
WIRE 3 2175 (-3550 3675)(-3550 3150);
WIRE 3 2175 (-4275 3675)(-4275 3150);
WIRE 3 2175 (-4275 3675)(-3550 3675);
WIRE 16 -1 (-6050 3425)(-6050 3450);
WIRE 16 -1 (-6050 3425)(-4175 3425);
FORCEPROP 0 LAST VOLTAGE 5
J 0
(-5950 3500);
DISPLAY 1.021277 (-5950 3500);
PAINT SKYBLUE (-5950 3500);
DISPLAY INVISIBLE (-5950 3500);
FORCEPROP 2 LAST SIG_NAME VR_PVSA_CPU0_PHASE
J 0
(-5959 3435);
DISPLAY 0.617021 (-5959 3435);
PAINT ORANGE (-5959 3435);
FORCEPROP 2 LASTPROP $XRERR UNIQUE?
J 0
(-6199 3435);
DISPLAY 0.638298 (-6199 3435);
PAINT MONO (-6199 3435);
DISPLAY INVISIBLE (-6199 3435);
WIRE 16 -1 (-4175 3425)(-4175 3575);
WIRE 16 -1 (-4175 3575)(-3650 3575);
WIRE 16 -1 (-3850 4875)(-1325 4875);
FORCEPROP 2 LAST SIG_NAME VR_PVSA_CPU0_BIREF1
J 0
(-2539 4900);
DISPLAY 0.617021 (-2539 4900);
PAINT ORANGE (-2539 4900);
WIRE 16 -1 (-3850 3525)(-3850 3725);
WIRE 16 -1 (-3650 3725)(-3850 3725);
WIRE 16 -1 (-3850 3725)(-3850 4875);
WIRE 16 -1 (-4975 2025)(-3800 2025);
FORCEPROP 2 LAST SIG_NAME VSENSE_PVSA_CPU0_SKT_VSEN
J 0
(-4745 2045);
DISPLAY 0.617021 (-4745 2045);
PAINT ORANGE (-4745 2045);
WIRE 16 -1 (-4975 1575)(-3800 1575);
FORCEPROP 2 LAST SIG_NAME VSENSE_PVSA_CPU0_SKT_VRTN
J 0
(-4745 1595);
DISPLAY 0.617021 (-4745 1595);
PAINT ORANGE (-4745 1595);
WIRE 16 -1 (-3650 3975)(-4425 3975);
FORCEPROP 0 LAST SIG_NAME TP_PVSA_CPU0_GL_1
J 0
(-4410 3985);
DISPLAY 0.617021 (-4410 3985);
PAINT ORANGE (-4410 3985);
FORCEPROP 2 LASTPROP $XRERR UNIQUE?
J 0
(-4665 3975);
DISPLAY 0.638298 (-4665 3975);
PAINT MONO (-4665 3975);
DISPLAY INVISIBLE (-4665 3975);
WIRE 16 -1 (-2025 4050)(-2025 4125);
WIRE 16 -1 (-2025 4125)(-1575 4125);
WIRE 16 -1 (-2650 4125)(-2650 3975);
WIRE 16 -1 (-2650 4125)(-2025 4125);
FORCEPROP 2 LAST SIG_NAME A_TSENSE_PVSA_CPU0
J 0
(-2654 4135);
DISPLAY 0.617021 (-2654 4135);
PAINT ORANGE (-2654 4135);
WIRE 16 -1 (-775 4275)(-775 4200);
WIRE 16 -1 (-2650 4275)(-775 4275);
FORCEPROP 0 LAST SIG_NAME VR_PVSA_CPU0_OCSET
J 0
(-2510 4285);
DISPLAY 0.617021 (-2510 4285);
PAINT ORANGE (-2510 4285);
FORCEPROP 2 LASTPROP $XRERR UNIQUE?
J 0
(-2750 4285);
DISPLAY 0.638298 (-2750 4285);
PAINT MONO (-2750 4285);
DISPLAY INVISIBLE (-2750 4285);
WIRE 3 682 (-2550 4225)(-2450 4225);
WIRE 16 -1 (-2650 4475)(-1400 4475);
FORCEPROP 2 LAST SIG_NAME ISENSE_PVSA_CPU0_IMON
J 0
(-2236 4487);
DISPLAY 0.617021 (-2236 4487);
PAINT ORANGE (-2236 4487);
WIRE 16 -1 (-3650 3925)(-4425 3925);
FORCEPROP 0 LAST SIG_NAME TP_PVSA_CPU0_GL_0
J 0
(-4410 3935);
DISPLAY 0.617021 (-4410 3935);
PAINT ORANGE (-4410 3935);
FORCEPROP 2 LASTPROP $XRERR UNIQUE?
J 0
(-4665 3925);
DISPLAY 0.638298 (-4665 3925);
PAINT MONO (-4665 3925);
DISPLAY INVISIBLE (-4665 3925);
WIRE 16 -1 (-4175 3625)(-3650 3625);
WIRE 16 -1 (-4175 3700)(-4175 3625);
WIRE 16 -1 (-5150 3700)(-4175 3700);
FORCEPROP 2 LAST SIG_NAME VR_PVSA_CPU0_BOOT_R
J 0
(-4909 3710);
DISPLAY 0.617021 (-4909 3710);
PAINT ORANGE (-4909 3710);
FORCEPROP 2 LASTPROP $XRERR UNIQUE?
J 0
(-5149 3710);
DISPLAY 0.638298 (-5149 3710);
PAINT MONO (-5149 3710);
DISPLAY INVISIBLE (-5149 3710);
WIRE 16 -1 (-6050 3700)(-6050 3650);
WIRE 16 -1 (-5350 3700)(-6050 3700);
FORCEPROP 2 LAST SIG_NAME VR_PVSA_CPU0_BOOT
J 0
(-6009 3710);
DISPLAY 0.617021 (-6009 3710);
PAINT ORANGE (-6009 3710);
FORCEPROP 2 LASTPROP $XRERR UNIQUE?
J 0
(-6249 3710);
DISPLAY 0.638298 (-6249 3710);
PAINT MONO (-6249 3710);
DISPLAY INVISIBLE (-6249 3710);
WIRE 16 2175 (-6400 3750)(-5575 3750);
WIRE 16 2175 (-5575 3750)(-5575 3350);
WIRE 16 2175 (-6400 3750)(-6400 3350);
WIRE 16 2175 (-6400 3350)(-5575 3350);
WIRE 16 -1 (-5175 1200)(-5325 1200);
WIRE 16 -1 (-5325 1200)(-5325 1575);
WIRE 16 -1 (-5175 1575)(-5325 1575);
WIRE 16 -1 (-5750 1725)(-5750 1575);
WIRE 16 -1 (-5325 1575)(-5750 1575);
WIRE 16 -1 (-5975 1575)(-5750 1575);
WIRE 16 -1 (-5975 1800)(-5975 1575);
WIRE 16 -1 (-6300 1800)(-5975 1800);
WIRE 16 -1 (-6300 1600)(-6300 1800);
WIRE 16 -1 (-7175 1600)(-6300 1600);
FORCEPROP 2 LAST SIG_NAME VSENSE_PVSA_CPU0_N
J 0
(-7170 1620);
DISPLAY 0.617021 (-7170 1620);
PAINT ORANGE (-7170 1620);
WIRE 3 2175 (-2175 3700)(-1675 3700);
WIRE 3 2175 (-1675 4175)(-1675 3700);
WIRE 3 2175 (-2175 4175)(-2175 3700);
WIRE 3 2175 (-2175 4175)(-1675 4175);
WIRE 16 -1 (-2050 3325)(-2050 3375);
WIRE 16 -1 (-2050 3325)(-1575 3325);
FORCEPROP 2 LAST SIG_NAME VR_PVSA_CPU0_PHASE_SW_RC
J 0
(-1985 3335);
DISPLAY 0.510638 (-1985 3335);
PAINT ORANGE (-1985 3335);
FORCEPROP 2 LASTPROP $XRERR UNIQUE?
J 0
(-1545 3325);
DISPLAY 0.638298 (-1545 3325);
PAINT MONO (-1545 3325);
DISPLAY INVISIBLE (-1545 3325);
WIRE 16 -1 (-2050 3275)(-2050 3325);
WIRE 3 2175 (-2125 3675)(-1525 3675);
WIRE 3 2175 (-1525 3675)(-1525 2850);
WIRE 3 2175 (-2125 3675)(-2125 2850);
WIRE 3 2175 (-2125 2850)(-1525 2850);
WIRE 3 2175 (-5525 3775)(-5000 3775);
WIRE 3 2175 (-5000 3775)(-5000 3500);
WIRE 3 2175 (-5525 3775)(-5525 3500);
WIRE 3 2175 (-5525 3500)(-5000 3500);
WIRE 16 -1 (-6400 3825)(-3650 3825);
FORCEPROP 2 LAST SIG_NAME VR_PVSA_CPU0_PWM
J 0
(-6333 3835);
DISPLAY 0.617021 (-6333 3835);
PAINT ORANGE (-6333 3835);
WIRE 3 2175 (-6050 4550)(-5675 4550);
WIRE 3 2175 (-5675 4825)(-5675 4550);
WIRE 3 2175 (-6050 4825)(-6050 4550);
WIRE 3 2175 (-6050 4825)(-5675 4825);
WIRE 3 682 (-5675 4050)(-5575 4050);
WIRE 3 682 (-5675 4300)(-5675 4050);
WIRE 3 682 (-5575 4050)(-5575 4300);
WIRE 3 682 (-5575 4300)(-5675 4300);
WIRE 16 682 (-5125 4350)(-5125 3975);
WIRE 16 682 (-5775 4350)(-5125 4350);
WIRE 16 682 (-5775 3975)(-5125 3975);
WIRE 16 682 (-5775 3975)(-5775 4350);
WIRE 16 -1 (-6000 4725)(-5950 4725);
WIRE 16 -1 (-6000 4300)(-6000 4475);
WIRE 16 -1 (-6000 4475)(-6000 4725);
WIRE 16 -1 (-3650 4475)(-6000 4475);
FORCEPROP 0 LAST VOLTAGE 5
J 0
(-5375 4550);
DISPLAY 1.021277 (-5375 4550);
PAINT SKYBLUE (-5375 4550);
DISPLAY INVISIBLE (-5375 4550);
FORCEPROP 2 LAST SIG_NAME VR_PVSA_CPU0_VCIN
J 0
(-5959 4485);
DISPLAY 0.617021 (-5959 4485);
PAINT ORANGE (-5959 4485);
FORCEPROP 2 LASTPROP $XRERR UNIQUE?
J 0
(-6199 4485);
DISPLAY 0.638298 (-6199 4485);
PAINT MONO (-6199 4485);
DISPLAY INVISIBLE (-6199 4485);
WIRE 16 -1 (-2050 3575)(-2050 3625);
WIRE 16 -1 (-1475 3625)(-2050 3625);
WIRE 16 -1 (-2650 3625)(-2050 3625);
FORCEPROP 0 LAST VOLTAGE 5
J 0
(-2275 3700);
DISPLAY 1.021277 (-2275 3700);
PAINT SKYBLUE (-2275 3700);
DISPLAY INVISIBLE (-2275 3700);
FORCEPROP 2 LAST SIG_NAME VR_PVSA_CPU0_PHASE_SW
J 0
(-2585 3635);
DISPLAY 0.510638 (-2585 3635);
PAINT ORANGE (-2585 3635);
FORCEPROP 2 LASTPROP $XRERR UNIQUE?
J 0
(-2825 3635);
DISPLAY 0.638298 (-2825 3635);
PAINT MONO (-2825 3635);
DISPLAY INVISIBLE (-2825 3635);
WIRE 16 682 (-1200 875)(-1200 1600);
WIRE 16 682 (-350 875)(-1200 875);
WIRE 16 682 (-1200 1600)(-350 1600);
WIRE 16 682 (-350 1600)(-350 875);
DOT 1 (-2000 1050);
DOT 1 (-5625 3950);
DOT 1 (-5625 4725);
DOT 1 (-1050 3625);
DOT 1 (-275 2825);
DOT 1 (-5300 4725);
DOT 1 (-2050 3625);
DOT 1 (-950 3625);
DOT 1 (-4550 4725);
DOT 1 (-2475 3475);
DOT 1 (-3850 3725);
DOT 1 (-6925 3950);
DOT 1 (-7175 4375);
DOT 1 (-6925 4375);
DOT 1 (-6700 3950);
DOT 1 (-6700 4375);
DOT 1 (-6475 3950);
DOT 1 (-6475 4375);
DOT 1 (-6250 3950);
DOT 1 (-6000 3950);
DOT 1 (-3750 4275);
DOT 1 (-6250 4375);
DOT 1 (-6000 4475);
DOT 1 (-3775 4375);
DOT 1 (-2475 3375);
DOT 1 (-2475 3425);
DOT 1 (-2025 4125);
DOT 1 (-600 2825);
DOT 1 (-600 3625);
DOT 1 (-275 3625);
DOT 1 (-2000 1500);
DOT 1 (-5325 1575);
DOT 1 (-5750 1575);
DOT 1 (-5350 2025);
DOT 1 (-5750 2025);
DOT 1 (-2050 3325);
FORCENOTE
TDA21460
(-3325 4550) 0;
DISPLAY LEFT (-3325 4550);
DISPLAY 1.021277 (-3325 4550);
PAINT SKYBLUE (-3325 4550);
FORCENOTE
IOUT TDC=15A
(-1175 1175) 0;
DISPLAY LEFT (-1175 1175);
DISPLAY 0.808511 (-1175 1175);
PAINT PURPLE (-1175 1175);
FORCENOTE
TP FAB1 CHANGE PN 0310
(-5725 4375) 0;
DISPLAY LEFT (-5725 4375);
DISPLAY 1.021277 (-5725 4375);
PAINT RED (-5725 4375);
FORCENOTE
TP FAB1 ADD NET NAME 12/04
(-1500 3325) 0;
DISPLAY LEFT (-1500 3325);
DISPLAY 0.680851 (-1500 3325);
PAINT RED (-1500 3325);
FORCENOTE
TP FAB1 CO-LAY WITH TI PARTS 11/16
(-1725 3900) 0;
DISPLAY LEFT (-1725 3900);
DISPLAY 0.851064 (-1725 3900);
PAINT RED (-1725 3900);
FORCENOTE
TP FAB1 CHANGE L4C2 PN 0122
(-1650 3750) 0;
DISPLAY LEFT (-1650 3750);
DISPLAY 1.021277 (-1650 3750);
PAINT RED (-1650 3750);
FORCENOTE
ROUT AS DIFF PAIR
(-6365 1815) 0;
DISPLAY LEFT (-6365 1815);
DISPLAY 0.808511 (-6365 1815);
PAINT PURPLE (-6365 1815);
FORCENOTE
TP FAB1 CO-LAY WITH TI PARTS 11/16
(-5275 3300) 0;
DISPLAY LEFT (-5275 3300);
DISPLAY 0.851064 (-5275 3300);
PAINT RED (-5275 3300);
FORCENOTE
ROOM = PVSA_CPU0_VSENSE_VR
(-6865 815) 0;
DISPLAY LEFT (-6865 815);
DISPLAY 2.446809 (-6865 815);
PAINT PURPLE (-6865 815);
FORCENOTE
TP FAB1 CHANGE TO 0 OHM 0107
(-6050 4825) 0;
DISPLAY LEFT (-6050 4825);
DISPLAY 0.638298 (-6050 4825);
PAINT RED (-6050 4825);
FORCENOTE
SPOF
(-6330 3250) 0;
DISPLAY LEFT (-6330 3250);
DISPLAY 1.808511 (-6330 3250);
PAINT PURPLE (-6330 3250);
FORCENOTE
TP FAB1 DEL NET 0309
(-2425 4225) 0;
DISPLAY LEFT (-2425 4225);
DISPLAY 1.021277 (-2425 4225);
PAINT RED (-2425 4225);
FORCENOTE
SOCKET SIDE
(-4265 1840) 0;
DISPLAY LEFT (-4265 1840);
PAINT PURPLE (-4265 1840);
FORCENOTE
5MIL SPACING
(-6265 1665) 0;
DISPLAY LEFT (-6265 1665);
DISPLAY 0.808511 (-6265 1665);
PAINT PURPLE (-6265 1665);
FORCENOTE
VR CONTROLLER SIDE
(-7390 1840) 0;
DISPLAY LEFT (-7390 1840);
PAINT PURPLE (-7390 1840);
FORCENOTE
IOUT STEP=5A/US
(-1175 1075) 0;
DISPLAY LEFT (-1175 1075);
DISPLAY 0.808511 (-1175 1075);
PAINT PURPLE (-1175 1075);
FORCENOTE
VBOOT=0.9V
(-1175 925) 0;
DISPLAY LEFT (-1175 925);
DISPLAY 0.808511 (-1175 925);
PAINT PURPLE (-1175 925);
FORCENOTE
10MIL WIDTH
(-6240 1740) 0;
DISPLAY LEFT (-6240 1740);
DISPLAY 0.808511 (-6240 1740);
PAINT PURPLE (-6240 1740);
FORCENOTE
PVSA CPU0 VOLTAGE SENSE
(-6990 1465) 0;
DISPLAY LEFT (-6990 1465);
PAINT PURPLE (-6990 1465);
FORCENOTE
DC TOL = +/-5MV
(-1175 1275) 0;
DISPLAY LEFT (-1175 1275);
DISPLAY 0.808511 (-1175 1275);
PAINT PURPLE (-1175 1275);
FORCENOTE
SW FREQ=520 KHZ
(-1175 975) 0;
DISPLAY LEFT (-1175 975);
DISPLAY 0.808511 (-1175 975);
PAINT PURPLE (-1175 975);
FORCENOTE
IOUT DI/DT =20A/US
(-1175 1025) 0;
DISPLAY LEFT (-1175 1025);
DISPLAY 0.808511 (-1175 1025);
PAINT PURPLE (-1175 1025);
FORCENOTE
IOUT PK=16A
(-1175 1125) 0;
DISPLAY LEFT (-1175 1125);
DISPLAY 0.808511 (-1175 1125);
PAINT PURPLE (-1175 1125);
FORCENOTE
TOTAL TOL = 0.917MAX/0.779VMIN 
(-1175 1225) 0;
DISPLAY LEFT (-1175 1225);
DISPLAY 0.808511 (-1175 1225);
PAINT PURPLE (-1175 1225);
FORCENOTE
TP FAB1 CHANGE RES TO 1 OHM 0603 0107
(-2300 2625) 0;
DISPLAY LEFT (-2300 2625);
DISPLAY 1.021277 (-2300 2625);
PAINT RED (-2300 2625);
FORCENOTE
TP FAB1 CO-LAY WITH TI PARTS 11/16
(-2300 2700) 0;
DISPLAY LEFT (-2300 2700);
DISPLAY 0.851064 (-2300 2700);
PAINT RED (-2300 2700);
FORCENOTE
VOUT=0.85V (TYP) SVID
(-1175 1375) 0;
DISPLAY LEFT (-1175 1375);
DISPLAY 0.808511 (-1175 1375);
PAINT PURPLE (-1175 1375);
FORCENOTE
RIPPLE = +/- 10MV
(-1175 1325) 0;
DISPLAY LEFT (-1175 1325);
DISPLAY 0.808511 (-1175 1325);
PAINT PURPLE (-1175 1325);
FORCENOTE
ROOM=PVSA_CPU0_PWR_VR
(-3180 1860) 0;
DISPLAY LEFT (-3180 1860);
DISPLAY 2.446809 (-3180 1860);
PAINT PURPLE (-3180 1860);
FORCENOTE
ROOM = PVSA_CPU0_DECAP_VR
(-3265 665) 0;
DISPLAY LEFT (-3265 665);
DISPLAY 2.446809 (-3265 665);
PAINT PURPLE (-3265 665);
FORCENOTE
PLACE ON TOP
(-5755 3875) 0;
DISPLAY LEFT (-5755 3875);
DISPLAY 1.553191 (-5755 3875);
PAINT PURPLE (-5755 3875);
QUIT
